G04 ================== begin FILE IDENTIFICATION RECORD ==================*
G04 Layout Name:  9049_F0T_FAN_BOARD_MP5048_D_v02_20221209_0830.brd*
G04 Film Name:    gnd1*
G04 File Format:  Gerber RS274X*
G04 File Origin:  Cadence Allegro 17.2-S081*
G04 Origin Date:  Mon Dec 12 15:05:04 2022*
G04 *
G04 Layer:  DRAWING FORMAT/TITLE_BLOCK_A*
G04 Layer:  PIN/SPECIAL_DRILL*
G04 Layer:  DRAWING FORMAT/TITLE_BLOCK*
G04 Layer:  VIA CLASS/GND1*
G04 Layer:  PIN/GND1*
G04 Layer:  MANUFACTURING/PHOTOPLOT_OUTLINE*
G04 Layer:  ETCH/GND1*
G04 Layer:  DRAWING FORMAT/TITLE_DATA_GND1*
G04 *
G04 Offset:    (0.00 0.00)*
G04 Mirror:    No*
G04 Mode:      Negative*
G04 Rotation:  0*
G04 FullContactRelief:  No*
G04 UndefLineWidth:     6.00*
G04 ================== end FILE IDENTIFICATION RECORD ====================*
%FSLAX25Y25*MOIN*%
%IR0*IPPOS*OFA0.00000B0.00000*MIA0B0*SFA1.00000B1.00000*%
%AMMACRO26*
4,1,46,.05906,.17844,
.059724,.155545,
.06128,.13665,
.09787,-.20608,
.098198,-.223234,
.095542,-.240184,
.089983,-.256415,
.081691,-.271435,
.070916,-.284786,
.057986,-.296063,
.043294,-.304924,
.027287,-.311099,
.010451,-.314401,
-.006703,-.314729,
-.023653,-.312073,
-.039884,-.306514,
-.054904,-.298221,
-.068255,-.287446,
-.079532,-.274517,
-.088393,-.259825,
-.094568,-.243818,
-.09787,-.226982,
-.098198,-.209828,
-.09787,-.20608,
-.06128,.13665,
-.059515,.159487,
-.05906,.17844,
-.05906,.25591,
-.058163,.266166,
-.055498,.27611,
-.051147,.28544,
-.045243,.293873,
-.037963,.301153,
-.02953,.307057,
-.0202,.311408,
-.010256,.314073,
0.0,.31497,
.010256,.314073,
.0202,.311408,
.02953,.307057,
.037963,.301153,
.045243,.293873,
.051147,.28544,
.055498,.27611,
.058163,.266166,
.05906,.25591,
.05906,.17844,
0.0*
%
%ADD26MACRO26*%
%ADD17C,.03*%
%AMMACRO27*
4,1,36,0.0,.005,
.000868,.004924,
.00171,.004698,
.0025,.00433,
.003214,.00383,
.00383,.003214,
.00433,.0025,
.004698,.00171,
.004924,.000868,
.005,0.0,
.004924,-.000868,
.004698,-.00171,
.00433,-.0025,
.00383,-.003214,
.003214,-.00383,
.0025,-.00433,
.00171,-.004698,
.000868,-.004924,
0.0,-.005,
-.000868,-.004924,
-.00171,-.004698,
-.0025,-.00433,
-.003214,-.00383,
-.00383,-.003214,
-.00433,-.0025,
-.004698,-.00171,
-.004924,-.000868,
-.005,0.0,
-.004924,.000868,
-.004698,.00171,
-.00433,.0025,
-.00383,.003214,
-.003214,.00383,
-.0025,.00433,
-.00171,.004698,
-.000868,.004924,
0.0,.005,
0.0*
%
%ADD27MACRO27*%
%AMMACRO29*
4,1,36,.0025,0.0,
.002462,.000434,
.002349,.000855,
.002165,.00125,
.001915,.001607,
.001607,.001915,
.00125,.002165,
.000855,.002349,
.000434,.002462,
0.0,.0025,
-.000434,.002462,
-.000855,.002349,
-.00125,.002165,
-.001607,.001915,
-.001915,.001607,
-.002165,.00125,
-.002349,.000855,
-.002462,.000434,
-.0025,0.0,
-.002462,-.000434,
-.002349,-.000855,
-.002165,-.00125,
-.001915,-.001607,
-.001607,-.001915,
-.00125,-.002165,
-.000855,-.002349,
-.000434,-.002462,
0.0,-.0025,
.000434,-.002462,
.000855,-.002349,
.00125,-.002165,
.001607,-.001915,
.001915,-.001607,
.002165,-.00125,
.002349,-.000855,
.002462,-.000434,
.0025,0.0,
270.*
%
%ADD29MACRO29*%
%AMMACRO24*
4,1,36,.0025,0.0,
.002462,.000434,
.002349,.000855,
.002165,.00125,
.001915,.001607,
.001607,.001915,
.00125,.002165,
.000855,.002349,
.000434,.002462,
0.0,.0025,
-.000434,.002462,
-.000855,.002349,
-.00125,.002165,
-.001607,.001915,
-.001915,.001607,
-.002165,.00125,
-.002349,.000855,
-.002462,.000434,
-.0025,0.0,
-.002462,-.000434,
-.002349,-.000855,
-.002165,-.00125,
-.001915,-.001607,
-.001607,-.001915,
-.00125,-.002165,
-.000855,-.002349,
-.000434,-.002462,
0.0,-.0025,
.000434,-.002462,
.000855,-.002349,
.00125,-.002165,
.001607,-.001915,
.001915,-.001607,
.002165,-.00125,
.002349,-.000855,
.002462,-.000434,
.0025,0.0,
180.*
%
%ADD24MACRO24*%
%AMMACRO25*
4,1,36,-.0025,0.0,
-.002462,.000434,
-.002349,.000855,
-.002165,.00125,
-.001915,.001607,
-.001607,.001915,
-.00125,.002165,
-.000855,.002349,
-.000434,.002462,
0.0,.0025,
.000434,.002462,
.000855,.002349,
.00125,.002165,
.001607,.001915,
.001915,.001607,
.002165,.00125,
.002349,.000855,
.002462,.000434,
.0025,0.0,
.002462,-.000434,
.002349,-.000855,
.002165,-.00125,
.001915,-.001607,
.001607,-.001915,
.00125,-.002165,
.000855,-.002349,
.000434,-.002462,
0.0,-.0025,
-.000434,-.002462,
-.000855,-.002349,
-.00125,-.002165,
-.001607,-.001915,
-.001915,-.001607,
-.002165,-.00125,
-.002349,-.000855,
-.002462,-.000434,
-.0025,0.0,
180.*
%
%ADD25MACRO25*%
%AMMACRO23*
4,1,36,-.0025,0.0,
-.002462,.000434,
-.002349,.000855,
-.002165,.00125,
-.001915,.001607,
-.001607,.001915,
-.00125,.002165,
-.000855,.002349,
-.000434,.002462,
0.0,.0025,
.000434,.002462,
.000855,.002349,
.00125,.002165,
.001607,.001915,
.001915,.001607,
.002165,.00125,
.002349,.000855,
.002462,.000434,
.0025,0.0,
.002462,-.000434,
.002349,-.000855,
.002165,-.00125,
.001915,-.001607,
.001607,-.001915,
.00125,-.002165,
.000855,-.002349,
.000434,-.002462,
0.0,-.0025,
-.000434,-.002462,
-.000855,-.002349,
-.00125,-.002165,
-.001607,-.001915,
-.001915,-.001607,
-.002165,-.00125,
-.002349,-.000855,
-.002462,-.000434,
-.0025,0.0,
270.*
%
%ADD23MACRO23*%
%ADD21C,.058*%
%ADD12C,.087*%
%ADD20C,.089*%
%AMMACRO30*
4,1,18,.10783,.07955,
.120006,.059617,
.128535,.037873,
.133159,.014977,
.133736,-.008373,
.130251,-.031469,
.122807,-.053609,
.111633,-.074119,
.10783,-.07955,
.11284,-.08455,
.125808,-.063671,
.134953,-.040857,
.139997,-.016802,
.140788,.007763,
.137301,.032093,
.129642,.055447,
.118045,.077117,
.11284,.08455,
.10783,.07955,
0.0*
4,1,18,.07955,-.10783,
.059617,-.120006,
.037873,-.128535,
.014977,-.133159,
-.008373,-.133736,
-.031469,-.130251,
-.053609,-.122807,
-.074119,-.111633,
-.07955,-.10783,
-.08455,-.11284,
-.063671,-.125808,
-.040857,-.134953,
-.016802,-.139997,
.007763,-.140788,
.032093,-.137301,
.055447,-.129642,
.077117,-.118045,
.08455,-.11284,
.07955,-.10783,
0.0*
4,1,18,-.10783,-.07955,
-.120006,-.059617,
-.128535,-.037873,
-.133159,-.014977,
-.133736,.008373,
-.130251,.031469,
-.122807,.053609,
-.111633,.074119,
-.10783,.07955,
-.11284,.08455,
-.125808,.063671,
-.134953,.040857,
-.139997,.016802,
-.140788,-.007763,
-.137301,-.032093,
-.129642,-.055447,
-.118045,-.077117,
-.11284,-.08455,
-.10783,-.07955,
0.0*
4,1,18,-.07955,.10783,
-.059617,.120006,
-.037873,.128535,
-.014977,.133159,
.008373,.133736,
.031469,.130251,
.053609,.122807,
.074119,.111633,
.07955,.10783,
.08455,.11284,
.063671,.125808,
.040857,.134953,
.016802,.139997,
-.007763,.140788,
-.032093,.137301,
-.055447,.129642,
-.077117,.118045,
-.08455,.11284,
-.07955,.10783,
0.0*
%
%ADD30MACRO30*%
%AMMACRO31*
4,1,15,-.02364,.01304,
-.025545,.008737,
-.026674,.004168,
-.026993,-.000527,
-.026491,-.005206,
-.025185,-.009727,
-.02364,-.01304,
-.02875,-.01815,
-.031465,-.012882,
-.033224,-.007222,
-.033973,-.001343,
-.03369,.004576,
-.032384,.010357,
-.030093,.015823,
-.02875,.01815,
-.02364,.01304,
90.*
4,1,15,-.01304,-.02364,
-.008737,-.025545,
-.004168,-.026674,
.000527,-.026993,
.005206,-.026491,
.009727,-.025185,
.01304,-.02364,
.01815,-.02875,
.012882,-.031465,
.007222,-.033224,
.001343,-.033973,
-.004576,-.03369,
-.010357,-.032384,
-.015823,-.030093,
-.01815,-.02875,
-.01304,-.02364,
90.*
4,1,15,.02364,-.01304,
.025545,-.008737,
.026674,-.004168,
.026993,.000527,
.026491,.005206,
.025185,.009727,
.02364,.01304,
.02875,.01815,
.031465,.012882,
.033224,.007222,
.033973,.001343,
.03369,-.004576,
.032384,-.010357,
.030093,-.015823,
.02875,-.01815,
.02364,-.01304,
90.*
4,1,15,.01304,.02364,
.008737,.025545,
.004168,.026674,
-.000527,.026993,
-.005206,.026491,
-.009727,.025185,
-.01304,.02364,
-.01815,.02875,
-.012882,.031465,
-.007222,.033224,
-.001343,.033973,
.004576,.03369,
.010357,.032384,
.015823,.030093,
.01815,.02875,
.01304,.02364,
90.*
%
%ADD31MACRO31*%
%AMMACRO14*
4,1,15,.03682,.01914,
.039584,.012455,
.041146,.005393,
.041457,-.001834,
.040509,-.009005,
.03833,-.015903,
.03682,-.01914,
.04197,-.0243,
.045552,-.016643,
.04775,-.00848,
.048497,-.000059,
.047771,.008363,
.045593,.016531,
.042029,.024197,
.04197,.0243,
.03682,.01914,
0.0*
4,1,15,.01914,-.03682,
.012455,-.039584,
.005393,-.041146,
-.001834,-.041457,
-.009005,-.040509,
-.015903,-.03833,
-.01914,-.03682,
-.0243,-.04197,
-.016643,-.045552,
-.00848,-.04775,
-.000059,-.048497,
.008363,-.047771,
.016531,-.045593,
.024197,-.042029,
.0243,-.04197,
.01914,-.03682,
0.0*
4,1,15,-.03682,-.01914,
-.039584,-.012455,
-.041146,-.005393,
-.041457,.001834,
-.040509,.009005,
-.03833,.015903,
-.03682,.01914,
-.04197,.0243,
-.045552,.016643,
-.04775,.00848,
-.048497,.000059,
-.047771,-.008363,
-.045593,-.016531,
-.042029,-.024197,
-.04197,-.0243,
-.03682,-.01914,
0.0*
4,1,15,-.01914,.03682,
-.012455,.039584,
-.005393,.041146,
.001834,.041457,
.009005,.040509,
.015903,.03833,
.01914,.03682,
.0243,.04197,
.016643,.045552,
.00848,.04775,
.000059,.048497,
-.008363,.047771,
-.016531,.045593,
-.024197,.042029,
-.0243,.04197,
-.01914,.03682,
0.0*
%
%ADD14MACRO14*%
%AMMACRO11*
4,1,15,-.03682,.01914,
-.039584,.012455,
-.041146,.005393,
-.041457,-.001834,
-.040509,-.009005,
-.03833,-.015903,
-.03682,-.01914,
-.04197,-.0243,
-.045552,-.016643,
-.04775,-.00848,
-.048497,-.000059,
-.047771,.008363,
-.045593,.016531,
-.042029,.024197,
-.04197,.0243,
-.03682,.01914,
0.0*
4,1,15,-.01914,-.03682,
-.012455,-.039584,
-.005393,-.041146,
.001834,-.041457,
.009005,-.040509,
.015903,-.03833,
.01914,-.03682,
.0243,-.04197,
.016643,-.045552,
.00848,-.04775,
.000059,-.048497,
-.008363,-.047771,
-.016531,-.045593,
-.024197,-.042029,
-.0243,-.04197,
-.01914,-.03682,
0.0*
4,1,15,.03682,-.01914,
.039584,-.012455,
.041146,-.005393,
.041457,.001834,
.040509,.009005,
.03833,.015903,
.03682,.01914,
.04197,.0243,
.045552,.016643,
.04775,.00848,
.048497,.000059,
.047771,-.008363,
.045593,-.016531,
.042029,-.024197,
.04197,-.0243,
.03682,-.01914,
0.0*
4,1,15,.01914,.03682,
.012455,.039584,
.005393,.041146,
-.001834,.041457,
-.009005,.040509,
-.015903,.03833,
-.01914,.03682,
-.0243,.04197,
-.016643,.045552,
-.00848,.04775,
-.000059,.048497,
.008363,.047771,
.016531,.045593,
.024197,.042029,
.0243,.04197,
.01914,.03682,
0.0*
%
%ADD11MACRO11*%
%ADD10C,.125*%
%ADD28C,.155*%
%AMMACRO16*
4,1,36,.0025,0.0,
.002462,.000434,
.002349,.000855,
.002165,.00125,
.001915,.001607,
.001607,.001915,
.00125,.002165,
.000855,.002349,
.000434,.002462,
0.0,.0025,
-.000434,.002462,
-.000855,.002349,
-.00125,.002165,
-.001607,.001915,
-.001915,.001607,
-.002165,.00125,
-.002349,.000855,
-.002462,.000434,
-.0025,0.0,
-.002462,-.000434,
-.002349,-.000855,
-.002165,-.00125,
-.001915,-.001607,
-.001607,-.001915,
-.00125,-.002165,
-.000855,-.002349,
-.000434,-.002462,
0.0,-.0025,
.000434,-.002462,
.000855,-.002349,
.00125,-.002165,
.001607,-.001915,
.001915,-.001607,
.002165,-.00125,
.002349,-.000855,
.002462,-.000434,
.0025,0.0,
90.*
%
%ADD16MACRO16*%
%AMMACRO18*
4,1,36,.0025,0.0,
.002462,.000434,
.002349,.000855,
.002165,.00125,
.001915,.001607,
.001607,.001915,
.00125,.002165,
.000855,.002349,
.000434,.002462,
0.0,.0025,
-.000434,.002462,
-.000855,.002349,
-.00125,.002165,
-.001607,.001915,
-.001915,.001607,
-.002165,.00125,
-.002349,.000855,
-.002462,.000434,
-.0025,0.0,
-.002462,-.000434,
-.002349,-.000855,
-.002165,-.00125,
-.001915,-.001607,
-.001607,-.001915,
-.00125,-.002165,
-.000855,-.002349,
-.000434,-.002462,
0.0,-.0025,
.000434,-.002462,
.000855,-.002349,
.00125,-.002165,
.001607,-.001915,
.001915,-.001607,
.002165,-.00125,
.002349,-.000855,
.002462,-.000434,
.0025,0.0,
0.0*
%
%ADD18MACRO18*%
%AMMACRO19*
4,1,36,-.0025,0.0,
-.002462,.000434,
-.002349,.000855,
-.002165,.00125,
-.001915,.001607,
-.001607,.001915,
-.00125,.002165,
-.000855,.002349,
-.000434,.002462,
0.0,.0025,
.000434,.002462,
.000855,.002349,
.00125,.002165,
.001607,.001915,
.001915,.001607,
.002165,.00125,
.002349,.000855,
.002462,.000434,
.0025,0.0,
.002462,-.000434,
.002349,-.000855,
.002165,-.00125,
.001915,-.001607,
.001607,-.001915,
.00125,-.002165,
.000855,-.002349,
.000434,-.002462,
0.0,-.0025,
-.000434,-.002462,
-.000855,-.002349,
-.00125,-.002165,
-.001607,-.001915,
-.001915,-.001607,
-.002165,-.00125,
-.002349,-.000855,
-.002462,-.000434,
-.0025,0.0,
0.0*
%
%ADD19MACRO19*%
%AMMACRO22*
4,1,15,-.02364,.01304,
-.025545,.008737,
-.026674,.004168,
-.026993,-.000527,
-.026491,-.005206,
-.025185,-.009727,
-.02364,-.01304,
-.02875,-.01815,
-.031465,-.012882,
-.033224,-.007222,
-.033973,-.001343,
-.03369,.004576,
-.032384,.010357,
-.030093,.015823,
-.02875,.01815,
-.02364,.01304,
270.*
4,1,15,-.01304,-.02364,
-.008737,-.025545,
-.004168,-.026674,
.000527,-.026993,
.005206,-.026491,
.009727,-.025185,
.01304,-.02364,
.01815,-.02875,
.012882,-.031465,
.007222,-.033224,
.001343,-.033973,
-.004576,-.03369,
-.010357,-.032384,
-.015823,-.030093,
-.01815,-.02875,
-.01304,-.02364,
270.*
4,1,15,.02364,-.01304,
.025545,-.008737,
.026674,-.004168,
.026993,.000527,
.026491,.005206,
.025185,.009727,
.02364,.01304,
.02875,.01815,
.031465,.012882,
.033224,.007222,
.033973,.001343,
.03369,-.004576,
.032384,-.010357,
.030093,-.015823,
.02875,-.01815,
.02364,-.01304,
270.*
4,1,15,.01304,.02364,
.008737,.025545,
.004168,.026674,
-.000527,.026993,
-.005206,.026491,
-.009727,.025185,
-.01304,.02364,
-.01815,.02875,
-.012882,.031465,
-.007222,.033224,
-.001343,.033973,
.004576,.03369,
.010357,.032384,
.015823,.030093,
.01815,.02875,
.01304,.02364,
270.*
%
%ADD22MACRO22*%
%AMMACRO13*
4,1,15,.03682,.01914,
.039584,.012455,
.041146,.005393,
.041457,-.001834,
.040509,-.009005,
.03833,-.015903,
.03682,-.01914,
.04197,-.0243,
.045552,-.016643,
.04775,-.00848,
.048497,-.000059,
.047771,.008363,
.045593,.016531,
.042029,.024197,
.04197,.0243,
.03682,.01914,
180.*
4,1,15,.01914,-.03682,
.012455,-.039584,
.005393,-.041146,
-.001834,-.041457,
-.009005,-.040509,
-.015903,-.03833,
-.01914,-.03682,
-.0243,-.04197,
-.016643,-.045552,
-.00848,-.04775,
-.000059,-.048497,
.008363,-.047771,
.016531,-.045593,
.024197,-.042029,
.0243,-.04197,
.01914,-.03682,
180.*
4,1,15,-.03682,-.01914,
-.039584,-.012455,
-.041146,-.005393,
-.041457,.001834,
-.040509,.009005,
-.03833,.015903,
-.03682,.01914,
-.04197,.0243,
-.045552,.016643,
-.04775,.00848,
-.048497,.000059,
-.047771,-.008363,
-.045593,-.016531,
-.042029,-.024197,
-.04197,-.0243,
-.03682,-.01914,
180.*
4,1,15,-.01914,.03682,
-.012455,.039584,
-.005393,.041146,
.001834,.041457,
.009005,.040509,
.015903,.03833,
.01914,.03682,
.0243,.04197,
.016643,.045552,
.00848,.04775,
.000059,.048497,
-.008363,.047771,
-.016531,.045593,
-.024197,.042029,
-.0243,.04197,
-.01914,.03682,
180.*
%
%ADD13MACRO13*%
%AMMACRO15*
4,1,15,-.03682,.01914,
-.039584,.012455,
-.041146,.005393,
-.041457,-.001834,
-.040509,-.009005,
-.03833,-.015903,
-.03682,-.01914,
-.04197,-.0243,
-.045552,-.016643,
-.04775,-.00848,
-.048497,-.000059,
-.047771,.008363,
-.045593,.016531,
-.042029,.024197,
-.04197,.0243,
-.03682,.01914,
180.*
4,1,15,-.01914,-.03682,
-.012455,-.039584,
-.005393,-.041146,
.001834,-.041457,
.009005,-.040509,
.015903,-.03833,
.01914,-.03682,
.0243,-.04197,
.016643,-.045552,
.00848,-.04775,
.000059,-.048497,
-.008363,-.047771,
-.016531,-.045593,
-.024197,-.042029,
-.0243,-.04197,
-.01914,-.03682,
180.*
4,1,15,.03682,-.01914,
.039584,-.012455,
.041146,-.005393,
.041457,.001834,
.040509,.009005,
.03833,.015903,
.03682,.01914,
.04197,.0243,
.045552,.016643,
.04775,.00848,
.048497,.000059,
.047771,-.008363,
.045593,-.016531,
.042029,-.024197,
.04197,-.0243,
.03682,-.01914,
180.*
4,1,15,.01914,.03682,
.012455,.039584,
.005393,.041146,
-.001834,.041457,
-.009005,.040509,
-.015903,.03833,
-.01914,.03682,
-.0243,.04197,
-.016643,.045552,
-.00848,.04775,
-.000059,.048497,
.008363,.047771,
.016531,.045593,
.024197,.042029,
.0243,.04197,
.01914,.03682,
180.*
%
%ADD15MACRO15*%
%ADD32C,.006*%
%ADD37C,.07*%
%ADD36C,.07006*%
%ADD34C,.09906*%
%ADD35C,.10406*%
%ADD33C,.16506*%
G75*
%LPD*%
G75*
G36*
G01X-320500Y-470483D02*
X2967000D01*
Y2626000D01*
X-320500D01*
Y-470483D01*
G37*
%LPC*%
G75*
G36*
G01X-70000Y602000D02*
G02X-75874Y607874I0J5874D01*
G01Y1318898D01*
G02X-70000Y1324772I5874J0D01*
G01X-15748D01*
G02X-9874Y1318898I0J-5874D01*
G01Y607874D01*
G02X-15748Y602000I-5874J0D01*
G01X-70000D01*
G37*
G36*
G01X15748Y1324768D02*
X187795D01*
G02X201539Y1311024I0J-13744D01*
G01Y15748D01*
G02X187795Y2004I-13744J0D01*
G01X145559D01*
G02X145417Y2063I0J200D01*
G01X140803Y6677D01*
G02X140744Y6819I141J142D01*
G01Y43307D01*
G03X127287I-6729J0D01*
G01Y32285D01*
G02X127087Y32085I-200J0D01*
G01X110354D01*
G02X110154Y32285I0J200D01*
G01Y36019D01*
G02X110231Y36177I200J0D01*
G01X110518Y36400D01*
X110608Y36419D01*
X110653Y36407D01*
G03X111522Y36298I867J3393D01*
G03X112941Y36598I1J3502D01*
G02X113103I81J-183D01*
G03X114522Y36298I1418J3202D01*
G03X118024Y39800I0J3502D01*
G03X117819Y40982I-3502J1D01*
G02Y41118I188J68D01*
G03X118024Y42300I-3297J1181D01*
G03X117819Y43482I-3502J1D01*
G02Y43618I188J68D01*
G03X118024Y44800I-3297J1181D01*
G03X117819Y45982I-3502J1D01*
G02Y46118I188J68D01*
G03X118024Y47300I-3297J1181D01*
G03X117819Y48482I-3502J1D01*
G02Y48618I188J68D01*
G03X118024Y49800I-3297J1181D01*
G03X117819Y50982I-3502J1D01*
G02Y51118I188J68D01*
G03X118024Y52300I-3297J1181D01*
G03X114522Y55802I-3502J0D01*
G03X113103Y55502I-1J-3502D01*
G02X112941I-81J183D01*
G03X111522Y55802I-1418J-3202D01*
G03X108020Y52300I0J-3502D01*
G03X108225Y51118I3502J-1D01*
G02Y50982I-188J-68D01*
G03X108020Y49800I3297J-1181D01*
G03X108225Y48618I3502J-1D01*
G02Y48482I-188J-68D01*
G03X108020Y47300I3297J-1181D01*
G03X108031Y47022I3502J-1D01*
G01X108034Y46973D01*
X107998Y46886D01*
X107680Y46612D01*
X107588Y46589D01*
X107541Y46600D01*
G03X106772Y46689I-771J-3293D01*
G03X103390Y43307I0J-3382D01*
G01Y32285D01*
G02X103190Y32085I-200J0D01*
G01X76456D01*
G02X76256Y32285I0J200D01*
G01Y43307D01*
G03X62799I-6729J0D01*
G01Y6819D01*
G02X62740Y6677I-200J0D01*
G01X58126Y2063D01*
G02X57984Y2004I-142J141D01*
G01X15748D01*
G02X2004Y15748I0J13744D01*
G01Y1039281D01*
X2000D01*
Y1040354D01*
X2004D01*
Y1311024D01*
G02X15748Y1324768I13744J0D01*
G37*
%LPD*%
G75*
G36*
G01X143818Y63294D02*
G02X145000Y63500I1183J-3294D01*
G02X146182Y63294I-1J-3500D01*
G03X146318I68J188D01*
G02X147500Y63500I1183J-3294D01*
G02X151000Y60000I0J-3500D01*
G02X150794Y58818I-3500J1D01*
G03Y58682I188J-68D01*
G02X151000Y57500I-3294J-1183D01*
G02X150794Y56318I-3500J1D01*
G03Y56182I188J-68D01*
G02X151000Y55000I-3294J-1183D01*
G02X147500Y51500I-3500J0D01*
G02X146318Y51706I1J3500D01*
G03X146182I-68J-188D01*
G02X145000Y51500I-1183J3294D01*
G02X143818Y51706I1J3500D01*
G03X143682I-68J-188D01*
G02X142500Y51500I-1183J3294D01*
G02X139143Y54008I0J3501D01*
G03X139008Y54143I-191J-56D01*
G02X138818Y54206I1006J3352D01*
G03X138682I-68J-188D01*
G02X137500Y54000I-1183J3294D01*
G02X134000Y57500I0J3500D01*
G02X134206Y58682I3500J-1D01*
G03Y58818I-188J68D01*
G02X134000Y60000I3294J1183D01*
G02X137500Y63500I3500J0D01*
G02X138682Y63294I-1J-3500D01*
G03X138818I68J188D01*
G02X140000Y63500I1183J-3294D01*
G02X141182Y63294I-1J-3500D01*
G03X141318I68J188D01*
G02X142500Y63500I1183J-3294D01*
G02X143682Y63294I-1J-3500D01*
G03X143818I68J188D01*
G37*
G36*
G01X78800Y77127D02*
X78832Y77242D01*
G03X78818Y77389I-192J56D01*
G02X78425Y79000I3107J1611D01*
G02X85425I3500J0D01*
G02X83716Y75993I-3500J0D01*
G03X83626Y75876I102J-172D01*
G01X83593Y75761D01*
G03X83608Y75614I193J-55D01*
G02X84002Y74000I-3109J-1614D01*
G02X76998I-3502J0D01*
G02X78710Y77010I3502J0D01*
G03X78800Y77127I-103J172D01*
G37*
G36*
G01X136200Y97805D02*
X135800Y97705D01*
X135731Y97646D01*
X135712Y97603D01*
G02X132500Y95498I-3212J1398D01*
G02Y102502I0J3502D01*
G02X134676Y101744I0J-3502D01*
G01X134713Y101715D01*
X134803Y101696D01*
X135203Y101795D01*
X135272Y101855D01*
X135291Y101898D01*
G02X138500Y104000I3209J-1398D01*
G02Y97000I0J-3500D01*
G02X136327Y97756I0J3501D01*
G01X136290Y97786D01*
X136200Y97805D01*
G37*
G36*
G01X125844Y103232D02*
G02X128000Y100000I-1345J-3232D01*
G02X124500Y96500I-3500J0D01*
G02X121268Y98656I0J3501D01*
G03X121160Y98764I-185J-77D01*
G02X118998Y102000I1341J3236D01*
G02X122500Y105502I3502J0D01*
G02X125736Y103340I0J-3503D01*
G03X125844Y103232I185J77D01*
G37*
G36*
G01X74190Y118924D02*
G02X77518Y121342I3328J-1081D01*
G02X81018Y117842I0J-3500D01*
G02X80119Y115500I-3500J0D01*
G03X80077Y115427I148J-134D01*
G02X76743Y112998I-3334J1074D01*
G02X73240Y116500I-1J3502D01*
G02X74148Y118852I3503J-1D01*
G03X74190Y118924I-148J135D01*
G37*
G36*
G01X145279Y147967D02*
G02X145074Y149149I3297J1181D01*
G02X148576Y152652I3502J1D01*
G02X149995Y152351I-2J-3503D01*
G03X150157I81J183D01*
G02X151576Y152652I1421J-3202D01*
G02X152995Y152351I-2J-3503D01*
G03X153157I81J183D01*
G02X154576Y152652I1421J-3202D01*
G02X158078Y149149I-1J-3503D01*
G02X157873Y147967I-3502J-1D01*
G03Y147831I188J-68D01*
G02X158078Y146649I-3297J-1181D01*
G02X154576Y143146I-3502J-1D01*
G02X153157Y143447I2J3503D01*
G03X152995I-81J-183D01*
G02X151576Y143146I-1421J3202D01*
G02X150157Y143447I2J3503D01*
G03X149995I-81J-183D01*
G02X148576Y143146I-1421J3202D01*
G02X145074Y146649I1J3503D01*
G02X145279Y147831I3502J1D01*
G03Y147967I-188J68D01*
G37*
G36*
G01X41157Y148340D02*
G02X40896Y149664I3241J1327D01*
G02X41102Y150846I3503J-2D01*
G03Y150982I-188J68D01*
G02X40896Y152164I3297J1184D01*
G02X44399Y155666I3503J-1D01*
G02X45818Y155366I1J-3502D01*
G03X45980I81J183D01*
G02X47399Y155666I1418J-3202D01*
G02X50902Y152164I1J-3502D01*
G02X50696Y150982I-3503J2D01*
G03Y150846I188J-68D01*
G02X50902Y149664I-3297J-1184D01*
G02X50641Y148340I-3502J3D01*
G03Y148188I186J-76D01*
G02X50902Y146864I-3241J-1327D01*
G02X47399Y143362I-3503J1D01*
G02X45980Y143662I-1J3502D01*
G03X45818I-81J-183D01*
G02X44399Y143362I-1418J3202D01*
G02X40896Y146864I-1J3502D01*
G02X41157Y148188I3502J-3D01*
G03Y148340I-186J76D01*
G37*
G36*
G01X45906Y168062D02*
G02X44487Y167762I-1418J3202D01*
G02X40984Y171264I-1J3502D01*
G02X41285Y172683I3503J-2D01*
G03Y172845I-183J81D01*
G02X40984Y174264I3202J1421D01*
G02X44487Y177766I3503J-1D01*
G02X45906Y177466I1J-3502D01*
G03X46068I81J183D01*
G02X47487Y177766I1418J-3202D01*
G02X50990Y174264I1J-3502D01*
G02X50689Y172845I-3503J2D01*
G03Y172683I183J-81D01*
G02X50990Y171264I-3202J-1421D01*
G02X47487Y167762I-3503J1D01*
G02X46068Y168062I-1J3502D01*
G03X45906I-81J-183D01*
G37*
G36*
G01X146462Y170024D02*
G02X146162Y171443I3202J1418D01*
G02X146462Y172862I3502J1D01*
G03Y173024I-183J81D01*
G02X146162Y174443I3202J1418D01*
G02X153166I3502J0D01*
G02X152866Y173024I-3502J-1D01*
G03Y172862I183J-81D01*
G02X153166Y171443I-3202J-1418D01*
G02X152866Y170024I-3502J-1D01*
G03Y169862I183J-81D01*
G02X153166Y168443I-3202J-1418D01*
G02X152866Y167024I-3502J-1D01*
G03Y166862I183J-81D01*
G02X153166Y165443I-3202J-1418D01*
G02X146162I-3502J0D01*
G02X146462Y166862I3502J1D01*
G03Y167024I-183J81D01*
G02X146162Y168443I3202J1418D01*
G02X146462Y169862I3502J1D01*
G03Y170024I-183J81D01*
G37*
G36*
G01X32715Y196218D02*
G02X30978Y199243I1766J3025D01*
G02X31278Y200662I3502J1D01*
G03Y200824I-183J81D01*
G02X30978Y202243I3202J1418D01*
G02X37982I3502J0D01*
G02X37682Y200824I-3502J-1D01*
G03Y200662I183J-81D01*
G02X37982Y199243I-3202J-1418D01*
G02X36303Y196252I-3502J-1D01*
G01X36257Y196224D01*
X36206Y196133D01*
X36211Y195682D01*
X36263Y195592D01*
X36309Y195565D01*
G02X38046Y192540I-1766J-3025D01*
G02X37746Y191121I-3502J-1D01*
G03Y190959I183J-81D01*
G02X38046Y189540I-3202J-1418D01*
G02X36108Y186406I-3503J0D01*
G01X36057Y186381D01*
X35999Y186288D01*
X35987Y185822D01*
X36042Y185727D01*
X36091Y185699D01*
G02X37882Y182643I-1712J-3056D01*
G02X37582Y181224I-3502J-1D01*
G03Y181062I183J-81D01*
G02X37882Y179643I-3202J-1418D01*
G02X30878I-3502J0D01*
G02X31178Y181062I3502J1D01*
G03Y181224I-183J81D01*
G02X30878Y182643I3202J1418D01*
G02X32816Y185777I3503J0D01*
G01X32867Y185802D01*
X32925Y185895D01*
X32937Y186361D01*
X32882Y186456D01*
X32833Y186484D01*
G02X31042Y189540I1712J3056D01*
G02X31342Y190959I3502J1D01*
G03Y191121I-183J81D01*
G02X31042Y192540I3202J1418D01*
G02X32721Y195531I3502J1D01*
G01X32767Y195559D01*
X32818Y195650D01*
X32813Y196101D01*
X32761Y196191D01*
X32715Y196218D01*
G37*
G36*
G01X32393Y208847D02*
G02X32694Y207428I-3202J-1421D01*
G02X25688I-3503J0D01*
G02X25989Y208847I3503J-2D01*
G03Y209009I-183J81D01*
G02X25688Y210428I3202J1421D01*
G02X32694I3503J0D01*
G02X32393Y209009I-3503J2D01*
G03Y208847I183J-81D01*
G37*
G36*
G01X176156Y228909D02*
G02X175856Y230328I3202J1418D01*
G02X179358Y233830I3502J0D01*
G02X180777Y233530I1J-3502D01*
G03X180939I81J183D01*
G02X182358Y233830I1418J-3202D01*
G02X183777Y233530I1J-3502D01*
G03X183939I81J183D01*
G02X185358Y233830I1418J-3202D01*
G02X188860Y230328I0J-3502D01*
G02X188560Y228909I-3502J-1D01*
G03Y228747I183J-81D01*
G02X188860Y227328I-3202J-1418D01*
G02X185358Y223826I-3502J0D01*
G02X183939Y224126I-1J3502D01*
G03X183777I-81J-183D01*
G02X182358Y223826I-1418J3202D01*
G02X180939Y224126I-1J3502D01*
G03X180777I-81J-183D01*
G02X179358Y223826I-1418J3202D01*
G02X175856Y227328I0J3502D01*
G02X176156Y228747I3502J1D01*
G03Y228909I-183J81D01*
G37*
G36*
G01X164361Y233883D02*
G02X165562Y234096I1203J-3290D01*
G02Y227090I0J-3503D01*
G02X164361Y227303I2J3503D01*
G03X164223I-69J-188D01*
G02X163022Y227090I-1203J3290D01*
G02Y234096I0J3503D01*
G02X164223Y233883I-2J-3503D01*
G03X164361I69J188D01*
G37*
G36*
G01X44977Y233313D02*
G02X44974Y233457I3500J145D01*
G02X48477Y236960I3503J0D01*
G02X49896Y236659I-2J-3503D01*
G03X50058I81J183D01*
G02X51477Y236960I1421J-3202D01*
G02X52896Y236659I-2J-3503D01*
G03X53058I81J183D01*
G02X54477Y236960I1421J-3202D01*
G02X57980Y233457I0J-3503D01*
G02X57616Y231903I-3503J1D01*
G03X57615Y231728I179J-89D01*
G02X57958Y230214I-3160J-1512D01*
G02X54456Y226712I-3502J0D01*
G02X53037Y227012I-1J3502D01*
G03X52875I-81J-183D01*
G02X51456Y226712I-1418J3202D01*
G02X50037Y227012I-1J3502D01*
G03X49875I-81J-183D01*
G02X48456Y226712I-1418J3202D01*
G02X45629Y228146I-1J3502D01*
G01X45601Y228185D01*
X45516Y228228D01*
X45098Y228229D01*
X45013Y228186D01*
X44985Y228147D01*
G02X42167Y226726I-2817J2082D01*
G02X40748Y227026I-1J3502D01*
G03X40586I-81J-183D01*
G02X39167Y226726I-1418J3202D01*
G02Y233730I0J3502D01*
G02X40586Y233430I1J-3502D01*
G03X40748I81J183D01*
G02X42167Y233730I1418J-3202D01*
G02X44331Y232982I1J-3502D01*
G01X44377Y232946D01*
X44493Y232935D01*
X44921Y233154D01*
X44980Y233254D01*
X44977Y233313D01*
G37*
G36*
G01X181077Y240326D02*
G02X179658Y240026I-1418J3202D01*
G02Y247030I0J3502D01*
G02X181077Y246730I1J-3502D01*
G03X181239I81J183D01*
G02X182658Y247030I1418J-3202D01*
G02X184077Y246730I1J-3502D01*
G03X184239I81J183D01*
G02X185658Y247030I1418J-3202D01*
G02Y240026I0J-3502D01*
G02X184239Y240326I-1J3502D01*
G03X184077I-81J-183D01*
G02X182658Y240026I-1418J3202D01*
G02X181239Y240326I-1J3502D01*
G03X181077I-81J-183D01*
G37*
G36*
G01X52386Y243026D02*
G02X50967Y242726I-1418J3202D01*
G02Y249730I0J3502D01*
G02X52386Y249430I1J-3502D01*
G03X52548I81J183D01*
G02X53967Y249730I1418J-3202D01*
G02X55386Y249430I1J-3502D01*
G03X55548I81J183D01*
G02X56967Y249730I1418J-3202D01*
G02Y242726I0J-3502D01*
G02X55548Y243026I-1J3502D01*
G03X55386I-81J-183D01*
G02X53967Y242726I-1418J3202D01*
G02X52548Y243026I-1J3502D01*
G03X52386I-81J-183D01*
G37*
G36*
G01X19766Y318430D02*
G02X21185Y318730I1418J-3202D01*
G02X22604Y318430I1J-3502D01*
G03X22766I81J183D01*
G02X24185Y318730I1418J-3202D01*
G02X25604Y318430I1J-3502D01*
G03X25766I81J183D01*
G02X27185Y318730I1418J-3202D01*
G02X30688Y315228I1J-3502D01*
G02X30387Y313809I-3503J2D01*
G03Y313647I183J-81D01*
G02X30688Y312228I-3202J-1421D01*
G02X27185Y308726I-3503J1D01*
G02X25766Y309026I-1J3502D01*
G03X25604I-81J-183D01*
G02X24185Y308726I-1418J3202D01*
G02X22766Y309026I-1J3502D01*
G03X22604I-81J-183D01*
G02X21185Y308726I-1418J3202D01*
G02X19766Y309026I-1J3502D01*
G03X19604I-81J-183D01*
G02X18185Y308726I-1418J3202D01*
G02X14682Y312228I-1J3502D01*
G02X14983Y313647I3503J-2D01*
G03Y313809I-183J81D01*
G02X14682Y315228I3202J1421D01*
G02X18185Y318730I3503J-1D01*
G02X19604Y318430I1J-3502D01*
G03X19766I81J183D01*
G37*
G36*
G01X124280Y313809D02*
G02X123980Y315228I3202J1418D01*
G02X127482Y318730I3502J0D01*
G02X128901Y318430I1J-3502D01*
G03X129063I81J183D01*
G02X130482Y318730I1418J-3202D01*
G02X131901Y318430I1J-3502D01*
G03X132063I81J183D01*
G02X133482Y318730I1418J-3202D01*
G02X136984Y315228I0J-3502D01*
G02X136684Y313809I-3502J-1D01*
G03Y313647I183J-81D01*
G02X136984Y312228I-3202J-1418D01*
G02X133482Y308726I-3502J0D01*
G02X132063Y309026I-1J3502D01*
G03X131901I-81J-183D01*
G02X130482Y308726I-1418J3202D01*
G02X129063Y309026I-1J3502D01*
G03X128901I-81J-183D01*
G02X127482Y308726I-1418J3202D01*
G02X123980Y312228I0J3502D01*
G02X124280Y313647I3502J1D01*
G03Y313809I-183J81D01*
G37*
G36*
G01X38766Y319430D02*
G02X40185Y319730I1418J-3202D01*
G02Y312726I0J-3502D01*
G02X38766Y313026I-1J3502D01*
G03X38604I-81J-183D01*
G02X37185Y312726I-1418J3202D01*
G02Y319730I0J3502D01*
G02X38604Y319430I1J-3502D01*
G03X38766I81J183D01*
G37*
G36*
G01X148063D02*
G02X149482Y319730I1418J-3202D01*
G02Y312726I0J-3502D01*
G02X148063Y313026I-1J3502D01*
G03X147901I-81J-183D01*
G02X146482Y312726I-1418J3202D01*
G02Y319730I0J3502D01*
G02X147901Y319430I1J-3502D01*
G03X148063I81J183D01*
G37*
G36*
G01X162060Y330647D02*
G02X162360Y329228I-3202J-1418D01*
G02X155356I-3502J0D01*
G02X155656Y330647I3502J1D01*
G03Y330809I-183J81D01*
G02X155356Y332228I3202J1418D01*
G02X162360I3502J0D01*
G02X162060Y330809I-3502J-1D01*
G03Y330647I183J-81D01*
G37*
G36*
G01X147856Y338390D02*
G02X148102Y337100I-3256J-1289D01*
G02X141098I-3502J0D01*
G02X141344Y338390I3502J1D01*
G03Y338538I-186J74D01*
G02X141098Y339828I3256J1289D01*
G02X148102I3502J0D01*
G02X147856Y338538I-3502J-1D01*
G03Y338390I186J-74D01*
G37*
G36*
G01X49703Y347315D02*
G02X49498Y348497I3297J1181D01*
G02X49703Y349679I3502J1D01*
G03Y349815I-188J68D01*
G02X49498Y350997I3297J1181D01*
G02X56502I3502J0D01*
G02X56297Y349815I-3502J-1D01*
G03Y349679I188J-68D01*
G02X56502Y348497I-3297J-1181D01*
G02X56297Y347315I-3502J-1D01*
G03Y347179I188J-68D01*
G02X56502Y346061I-3297J-1182D01*
G03X56648Y345872I200J4D01*
G02X59202Y342500I-949J-3372D01*
G02X55700Y338998I-3502J0D01*
G02X52198Y342436I0J3503D01*
G03X52052Y342625I-200J-4D01*
G02X49498Y345997I949J3372D01*
G02X49703Y347179I3502J1D01*
G03Y347315I-188J68D01*
G37*
G36*
G01X146644Y347738D02*
G02X146398Y349028I3256J1289D01*
G02X146652Y350339I3502J2D01*
G03Y350489I-185J75D01*
G02X146398Y351800I3248J1309D01*
G02X153402I3502J0D01*
G02X153148Y350489I-3502J-2D01*
G03Y350339I185J-75D01*
G02X153402Y349028I-3248J-1309D01*
G02X153156Y347738I-3502J-1D01*
G03Y347590I186J-74D01*
G02X153402Y346300I-3256J-1289D01*
G02X146398I-3502J0D01*
G02X146644Y347590I3502J1D01*
G03Y347738I-186J74D01*
G37*
G36*
G01X19081Y364930D02*
G02X20500Y365230I1418J-3202D01*
G02X21919Y364930I1J-3502D01*
G03X22081I81J183D01*
G02X23500Y365230I1418J-3202D01*
G02X24919Y364930I1J-3502D01*
G03X25081I81J183D01*
G02X26500Y365230I1418J-3202D01*
G02X30002Y361728I0J-3502D01*
G02X29702Y360309I-3502J-1D01*
G03Y360147I183J-81D01*
G02X30002Y358728I-3202J-1418D01*
G02X26500Y355226I-3502J0D01*
G02X25081Y355526I-1J3502D01*
G03X24919I-81J-183D01*
G02X23500Y355226I-1418J3202D01*
G02X22081Y355526I-1J3502D01*
G03X21919I-81J-183D01*
G02X20500Y355226I-1418J3202D01*
G02X19081Y355526I-1J3502D01*
G03X18919I-81J-183D01*
G02X17500Y355226I-1418J3202D01*
G02X13998Y358728I0J3502D01*
G02X14298Y360147I3502J1D01*
G03Y360309I-183J81D01*
G02X13998Y361728I3202J1418D01*
G02X17500Y365230I3502J0D01*
G02X18919Y364930I1J-3502D01*
G03X19081I81J183D01*
G37*
G36*
G01X178439Y365492D02*
G02X179858Y365792I1418J-3202D01*
G02X181277Y365492I1J-3502D01*
G03X181439I81J183D01*
G02X182858Y365792I1418J-3202D01*
G02X184277Y365492I1J-3502D01*
G03X184439I81J183D01*
G02X185858Y365792I1418J-3202D01*
G02X189360Y362290I0J-3502D01*
G02X189155Y361108I-3502J-1D01*
G03Y360972I188J-68D01*
G02X189360Y359790I-3297J-1181D01*
G02X185858Y356288I-3502J0D01*
G02X184439Y356588I-1J3502D01*
G03X184277I-81J-183D01*
G02X182858Y356288I-1418J3202D01*
G02X181439Y356588I-1J3502D01*
G03X181277I-81J-183D01*
G02X179858Y356288I-1418J3202D01*
G02X178439Y356588I-1J3502D01*
G03X178277I-81J-183D01*
G02X176858Y356288I-1418J3202D01*
G02X173356Y359790I0J3502D01*
G02X173561Y360972I3502J1D01*
G03Y361108I-188J68D01*
G02X173356Y362290I3297J1181D01*
G02X176858Y365792I3502J0D01*
G02X178277Y365492I1J-3502D01*
G03X178439I81J183D01*
G37*
G36*
G01X49703Y366315D02*
G02X49498Y367497I3297J1181D01*
G02X49703Y368679I3502J1D01*
G03Y368815I-188J68D01*
G02X49498Y369997I3297J1181D01*
G02X56502I3502J0D01*
G02X56297Y368815I-3502J-1D01*
G03Y368679I188J-68D01*
G02X56502Y367497I-3297J-1181D01*
G02X56297Y366315I-3502J-1D01*
G03Y366179I188J-68D01*
G02X56502Y364997I-3297J-1181D01*
G02X49498I-3502J0D01*
G02X49703Y366179I3502J1D01*
G03Y366315I-188J68D01*
G37*
G36*
G01X146748Y366001D02*
G02X146398Y367528I3152J1526D01*
G02X146652Y368839I3502J2D01*
G03Y368989I-185J75D01*
G02X146398Y370300I3248J1309D01*
G02X153402I3502J0D01*
G02X153148Y368989I-3502J-2D01*
G03Y368839I185J-75D01*
G02X153402Y367528I-3248J-1309D01*
G02X153052Y366001I-3502J-1D01*
G03Y365827I180J-87D01*
G02X153402Y364300I-3152J-1526D01*
G02X146398I-3502J0D01*
G02X146748Y365827I3502J1D01*
G03Y366001I-180J87D01*
G37*
G36*
G01X114199Y399670D02*
G02X117500Y402002I3301J-1170D01*
G02X121002Y398500I0J-3502D01*
G02X119850Y395903I-3503J0D01*
G03X119796Y395822I134J-148D01*
G02X116500Y393500I-3296J1178D01*
G02X113000Y397000I0J3500D01*
G02X114145Y399589I3500J0D01*
G03X114199Y399670I-135J148D01*
G37*
G36*
G01X74107Y462168D02*
G02X76855Y458750I-752J-3418D01*
G02X73355Y455250I-3500J0D01*
G02X70665Y456510I-1J3500D01*
G03X70554Y456578I-154J-127D01*
G02X67798Y460000I746J3422D01*
G02X71300Y463502I3502J0D01*
G02X73996Y462236I1J-3502D01*
G03X74107Y462168I154J127D01*
G37*
G36*
G01X124483Y465642D02*
G02X126008Y465992I1526J-3150D01*
G02Y458992I0J-3500D01*
G02X123746Y459822I1J3500D01*
G03X123529Y459849I-129J-153D01*
G02X122000Y459498I-1528J3151D01*
G02Y466502I0J3502D01*
G02X124267Y465670I1J-3502D01*
G03X124483Y465642I130J152D01*
G37*
G36*
G01X80748Y773831D02*
G02X80968Y772610I-3280J-1221D01*
G02X73968I-3500J0D01*
G02X74124Y773643I3500J0D01*
G03X74120Y773772I-191J59D01*
G02X73898Y775000I3280J1227D01*
G02X80902I3502J0D01*
G02X80745Y773960I-3502J-3D01*
G03X80748Y773831I191J-60D01*
G37*
G36*
G01X136726Y778071D02*
G02X137675Y775675I-2550J-2396D01*
G02X134175Y772175I-3500J0D01*
G02X131390Y773555I0J3500D01*
G03X131375Y773573I-161J-119D01*
G02X130398Y776000I2526J2427D01*
G02X133900Y779502I3502J0D01*
G02X136712Y778088I0J-3503D01*
G03X136726Y778071I161J119D01*
G37*
G36*
G01X74148Y825761D02*
G02X73518Y827764I2869J2003D01*
G02X77018Y831264I3500J0D01*
G02X77662Y831204I-1J-3500D01*
G03X77823Y831244I37J197D01*
G02X80000Y832002I2176J-2744D01*
G02X83502Y828500I0J-3502D01*
G02X80650Y825058I-3503J0D01*
G01X80607Y825050D01*
X80538Y825002D01*
X80340Y824671D01*
X80330Y824588D01*
X80343Y824546D01*
G02X80502Y823500I-3343J-1043D01*
G02X73498I-3502J0D01*
G02X74146Y825531I3502J1D01*
G03X74148Y825761I-163J116D01*
G37*
G36*
G01X45106Y878996D02*
G02X44806Y880415I3202J1418D01*
G02X45106Y881834I3502J1D01*
G03Y881996I-183J81D01*
G02X44806Y883415I3202J1418D01*
G02X48308Y886918I3502J1D01*
G02X49490Y886712I-2J-3503D01*
G03X49626I68J188D01*
G02X50808Y886918I1184J-3297D01*
G02X54310Y883415I-1J-3503D01*
G02X54010Y881996I-3502J-1D01*
G03Y881834I183J-81D01*
G02X54310Y880415I-3202J-1418D01*
G02X54010Y878996I-3502J-1D01*
G03Y878834I183J-81D01*
G02X54310Y877415I-3202J-1418D01*
G02X50808Y873912I-3502J-1D01*
G02X49626Y874118I2J3503D01*
G03X49490I-68J-188D01*
G02X48308Y873912I-1184J3297D01*
G02X44806Y877415I1J3503D01*
G02X45106Y878834I3502J1D01*
G03Y878996I-183J81D01*
G37*
G36*
G01X146662Y891696D02*
G02X146362Y893115I3202J1418D01*
G02X146662Y894534I3502J1D01*
G03Y894696I-183J81D01*
G02X146362Y896115I3202J1418D01*
G02X149864Y899618I3502J1D01*
G02X151046Y899412I-2J-3503D01*
G03X151182I68J188D01*
G02X152364Y899618I1184J-3297D01*
G02X155866Y896115I-1J-3503D01*
G02X155566Y894696I-3502J-1D01*
G03Y894534I183J-81D01*
G02X155866Y893115I-3202J-1418D01*
G02X155566Y891696I-3502J-1D01*
G03Y891534I183J-81D01*
G02X155866Y890115I-3202J-1418D01*
G02X152364Y886612I-3502J-1D01*
G02X151182Y886818I2J3503D01*
G03X151046I-68J-188D01*
G02X149864Y886612I-1184J3297D01*
G02X146362Y890115I1J3503D01*
G02X146662Y891534I3502J1D01*
G03Y891696I-183J81D01*
G37*
G36*
G01X35727Y905660D02*
G02X36028Y904241I-3202J-1421D01*
G02X29022I-3503J0D01*
G02X29323Y905660I3503J-2D01*
G03Y905822I-183J81D01*
G02X29022Y907241I3202J1421D01*
G02X36028I3503J0D01*
G02X35727Y905822I-3503J2D01*
G03Y905660I183J-81D01*
G37*
G36*
G01X166079Y911919D02*
G02X166380Y910500I-3202J-1421D01*
G02X159374I-3503J0D01*
G02X159675Y911919I3503J-2D01*
G03Y912081I-183J81D01*
G02X159374Y913500I3202J1421D01*
G02X166380I3503J0D01*
G02X166079Y912081I-3503J2D01*
G03Y911919I183J-81D01*
G37*
G36*
G01X161328Y928359D02*
G02X159374Y931500I1549J3142D01*
G02X159675Y932919I3503J-2D01*
G03Y933081I-183J81D01*
G02X159374Y934500I3202J1421D01*
G02X166380I3503J0D01*
G02X166079Y933081I-3503J2D01*
G03Y932919I183J-81D01*
G02X166380Y931500I-3202J-1421D01*
G02X164426Y928359I-3503J1D01*
G03X164315Y928179I89J-179D01*
G01Y927821D01*
G03X164426Y927641I200J-1D01*
G02X166380Y924500I-1549J-3142D01*
G02X166079Y923081I-3503J2D01*
G03Y922919I183J-81D01*
G02X166380Y921500I-3202J-1421D01*
G02X159374I-3503J0D01*
G02X159675Y922919I3503J-2D01*
G03Y923081I-183J81D01*
G02X159374Y924500I3202J1421D01*
G02X161328Y927641I3503J-1D01*
G03X161439Y927821I-89J179D01*
G01Y928179D01*
G03X161328Y928359I-200J1D01*
G37*
G36*
G01X30789Y936234D02*
G02X31090Y934815I-3202J-1421D01*
G02X24084I-3503J0D01*
G02X24385Y936234I3503J-2D01*
G03Y936396I-183J81D01*
G02X24084Y937815I3202J1421D01*
G02X31090I3503J0D01*
G02X30789Y936396I-3503J2D01*
G03Y936234I183J-81D01*
G37*
G36*
G01X171379Y941519D02*
G02X171680Y940100I-3202J-1421D01*
G02X164674I-3503J0D01*
G02X164975Y941519I3503J-2D01*
G03Y941681I-183J81D01*
G02X164674Y943100I3202J1421D01*
G02X171680I3503J0D01*
G02X171379Y941681I-3503J2D01*
G03Y941519I183J-81D01*
G37*
G36*
G01X182227Y949768D02*
G02X180658Y949398I-1567J3133D01*
G02X177156Y952900I0J3502D01*
G02X177499Y954414I3503J2D01*
G03Y954586I-180J86D01*
G02X177156Y956100I3160J1512D01*
G02X180658Y959602I3502J0D01*
G02X182022Y959326I1J-3502D01*
G03X182189Y959332I77J184D01*
G02X183758Y959702I1567J-3133D01*
G02X185241Y959373I1J-3502D01*
G03X185397Y959368I84J181D01*
G02X186658Y959602I1259J-3268D01*
G02X190160Y956100I0J-3502D01*
G02X189817Y954586I-3503J-2D01*
G03Y954414I180J-86D01*
G02X190160Y952900I-3160J-1512D01*
G02X186658Y949398I-3502J0D01*
G02X185175Y949727I-1J3502D01*
G03X185019Y949732I-84J-181D01*
G02X183758Y949498I-1259J3268D01*
G02X182394Y949774I-1J3502D01*
G03X182227Y949768I-77J-184D01*
G37*
G36*
G01X166439Y965002D02*
G02X167858Y965302I1418J-3202D01*
G02Y958298I0J-3502D01*
G02X166439Y958598I-1J3502D01*
G03X166277I-81J-183D01*
G02X164858Y958298I-1418J3202D01*
G02Y965302I0J3502D01*
G02X166277Y965002I1J-3502D01*
G03X166439I81J183D01*
G37*
G36*
G01X134981Y960683D02*
G02X134776Y961865I3297J1181D01*
G02X138278Y965368I3502J1D01*
G02X139460Y965162I-2J-3503D01*
G03X139596I68J188D01*
G02X140778Y965368I1184J-3297D01*
G02X141998Y965148I-2J-3503D01*
G03X142138I70J188D01*
G02X143358Y965368I1222J-3283D01*
G02X146860Y961865I-1J-3503D01*
G02X146655Y960683I-3502J-1D01*
G03Y960547I188J-68D01*
G02X146860Y959365I-3297J-1181D01*
G02X143358Y955862I-3502J-1D01*
G02X142157Y956075I2J3503D01*
G03X142019I-69J-188D01*
G02X140818Y955862I-1203J3290D01*
G02X139617Y956075I2J3503D01*
G03X139479I-69J-188D01*
G02X138278Y955862I-1203J3290D01*
G02X134776Y959365I1J3503D01*
G02X134981Y960547I3502J1D01*
G03Y960683I-188J68D01*
G37*
G36*
G01X147785Y963832D02*
G02X147580Y965014I3297J1181D01*
G02X151082Y968516I3502J0D01*
G02X152264Y968311I1J-3502D01*
G03X152400I68J188D01*
G02X153582Y968516I1181J-3297D01*
G02X154802Y968297I1J-3502D01*
G03X154942I70J188D01*
G02X156162Y968516I1219J-3283D01*
G02X159664Y965014I0J-3502D01*
G02X159459Y963832I-3502J-1D01*
G03Y963696I188J-68D01*
G02X159664Y962514I-3297J-1181D01*
G02X156162Y959012I-3502J0D01*
G02X154961Y959224I-1J3502D01*
G03X154823I-69J-188D01*
G02X153622Y959012I-1200J3290D01*
G02X152421Y959224I-1J3502D01*
G03X152283I-69J-188D01*
G02X151082Y959012I-1200J3290D01*
G02X147580Y962514I0J3502D01*
G02X147785Y963696I3502J1D01*
G03Y963832I-188J68D01*
G37*
G36*
G01X185019Y965832D02*
G02X183758Y965598I-1259J3268D01*
G02X182394Y965874I-1J3502D01*
G03X182227Y965868I-77J-184D01*
G02X180658Y965498I-1567J3133D01*
G02Y972502I0J3502D01*
G02X182022Y972226I1J-3502D01*
G03X182189Y972232I77J184D01*
G02X183758Y972602I1567J-3133D01*
G02X185241Y972273I1J-3502D01*
G03X185397Y972268I84J181D01*
G02X186658Y972502I1259J-3268D01*
G02Y965498I0J-3502D01*
G02X185175Y965827I-1J3502D01*
G03X185019Y965832I-84J-181D01*
G37*
G36*
G01X39166Y1044502D02*
G02X40585Y1044802I1418J-3202D01*
G02Y1037798I0J-3502D01*
G02X39166Y1038098I-1J3502D01*
G03X39004I-81J-183D01*
G02X37585Y1037798I-1418J3202D01*
G02Y1044802I0J3502D01*
G02X39004Y1044502I1J-3502D01*
G03X39166I81J183D01*
G37*
G36*
G01X123980Y1040581D02*
G02X123680Y1042000I3202J1418D01*
G02X127182Y1045502I3502J0D01*
G02X128696Y1045159I2J-3503D01*
G03X128868I86J180D01*
G02X130382Y1045502I1512J-3160D01*
G02X131801Y1045202I1J-3502D01*
G03X131963I81J183D01*
G02X133382Y1045502I1418J-3202D01*
G02X136884Y1042000I0J-3502D01*
G02X136584Y1040581I-3502J-1D01*
G03Y1040419I183J-81D01*
G02X136884Y1039000I-3202J-1418D01*
G02X133382Y1035498I-3502J0D01*
G02X131963Y1035798I-1J3502D01*
G03X131801I-81J-183D01*
G02X130382Y1035498I-1418J3202D01*
G02X128868Y1035841I-2J3503D01*
G03X128696I-86J-180D01*
G02X127182Y1035498I-1512J3160D01*
G02X123680Y1039000I0J3502D01*
G02X123980Y1040419I3502J1D01*
G03Y1040581I-183J81D01*
G37*
G36*
G01X148063Y1046202D02*
G02X149482Y1046502I1418J-3202D01*
G02Y1039498I0J-3502D01*
G02X148063Y1039798I-1J3502D01*
G03X147901I-81J-183D01*
G02X146482Y1039498I-1418J3202D01*
G02Y1046502I0J3502D01*
G02X147901Y1046202I1J-3502D01*
G03X148063I81J183D01*
G37*
G36*
G01X10209Y1048036D02*
G02X9990Y1049256I3283J1219D01*
G02X10195Y1050438I3502J1D01*
G03Y1050574I-188J68D01*
G02X9990Y1051756I3297J1181D01*
G02X16994I3502J0D01*
G02X16789Y1050574I-3502J-1D01*
G03Y1050438I188J-68D01*
G02X16994Y1049256I-3297J-1181D01*
G02X16775Y1048036I-3502J-1D01*
G03Y1047896I188J-70D01*
G02X16994Y1046676I-3283J-1219D01*
G02X16882Y1045794I-3502J-3D01*
G01X16868Y1045742D01*
X16895Y1045642D01*
X17210Y1045321D01*
X17311Y1045292D01*
X17363Y1045305D01*
G02X18185Y1045402I819J-3405D01*
G02X19699Y1045059I2J-3503D01*
G03X19871I86J180D01*
G02X21385Y1045402I1512J-3160D01*
G02X23041Y1044986I0J-3502D01*
G03X23219Y1044981I94J177D01*
G02X24685Y1045302I1465J-3181D01*
G02X28188Y1041800I1J-3502D01*
G02X27887Y1040381I-3503J2D01*
G03Y1040219I183J-81D01*
G02X28188Y1038800I-3202J-1421D01*
G02X24685Y1035298I-3503J1D01*
G02X23029Y1035714I0J3502D01*
G03X22851Y1035719I-94J-177D01*
G02X21385Y1035398I-1465J3181D01*
G02X19871Y1035741I-2J3503D01*
G03X19699I-86J-180D01*
G02X18185Y1035398I-1512J3160D01*
G02X14682Y1038900I-1J3502D01*
G02X14983Y1040319I3503J-2D01*
G03Y1040481I-183J81D01*
G02X14682Y1041900I3202J1421D01*
G02X14795Y1042782I3503J-1D01*
G01X14809Y1042834D01*
X14782Y1042934D01*
X14467Y1043255D01*
X14366Y1043284D01*
X14314Y1043271D01*
G02X13492Y1043174I-819J3405D01*
G02X9990Y1046676I0J3502D01*
G02X10209Y1047896I3502J1D01*
G03Y1048036I-188J70D01*
G37*
G36*
G01X128696Y1051841D02*
G02X127182Y1051498I-1512J3160D01*
G02Y1058502I0J3502D01*
G02X128696Y1058159I2J-3503D01*
G03X128868I86J180D01*
G02X130382Y1058502I1512J-3160D01*
G02X131801Y1058202I1J-3502D01*
G03X131963I81J183D01*
G02X133382Y1058502I1418J-3202D01*
G02Y1051498I0J-3502D01*
G02X131963Y1051798I-1J3502D01*
G03X131801I-81J-183D01*
G02X130382Y1051498I-1418J3202D01*
G02X128868Y1051841I-2J3503D01*
G03X128696I-86J-180D01*
G37*
G36*
G01X139775Y1074318D02*
G02X139570Y1075500I3297J1181D01*
G02X139775Y1076682I3502J1D01*
G03Y1076818I-188J68D01*
G02X139570Y1078000I3297J1181D01*
G02X146574I3502J0D01*
G02X146369Y1076818I-3502J-1D01*
G03Y1076682I188J-68D01*
G02X146574Y1075500I-3297J-1181D01*
G02X146369Y1074318I-3502J-1D01*
G03Y1074182I188J-68D01*
G02X146574Y1073000I-3297J-1181D01*
G02X145136Y1070170I-3502J-1D01*
G03X145055Y1070030I118J-162D01*
G02X144869Y1069218I-3483J370D01*
G03Y1069082I188J-68D01*
G02X145074Y1067900I-3297J-1181D01*
G02X138070I-3502J0D01*
G02X138275Y1069082I3502J1D01*
G03Y1069218I-188J68D01*
G02X138070Y1070400I3297J1181D01*
G02X139508Y1073230I3502J1D01*
G03X139589Y1073370I-118J162D01*
G02X139775Y1074182I3483J-370D01*
G03Y1074318I-188J68D01*
G37*
G36*
G01X52758Y1073977D02*
G02X52198Y1075878I2942J1900D01*
G02X52591Y1077491I3502J1D01*
G03Y1077676I-177J92D01*
G02X52198Y1079289I3109J1612D01*
G02X59202I3502J0D01*
G02X58809Y1077676I-3502J-1D01*
G03Y1077491I177J-93D01*
G02X59202Y1075878I-3109J-1612D01*
G02X58643Y1073978I-3503J-2D01*
G03Y1073761I168J-109D01*
G02X59204Y1071860I-2942J-1901D01*
G02X58810Y1070247I-3503J1D01*
G03Y1070062I177J-93D01*
G02X59204Y1068449I-3109J-1614D01*
G02X59149Y1067832I-3503J1D01*
G01X59139Y1067777D01*
X59177Y1067676D01*
X59536Y1067386D01*
X59643Y1067370D01*
X59695Y1067391D01*
G02X61029Y1067656I1336J-3238D01*
G02X64532Y1064153I0J-3503D01*
G02X64138Y1062540I-3503J1D01*
G03Y1062355I177J-92D01*
G02X64532Y1060742I-3109J-1614D01*
G02X57526I-3503J0D01*
G02X57920Y1062355I3503J-1D01*
G03Y1062540I-177J93D01*
G02X57526Y1064153I3109J1614D01*
G02X57581Y1064770I3503J-1D01*
G01X57591Y1064825D01*
X57553Y1064926D01*
X57194Y1065216D01*
X57087Y1065232D01*
X57035Y1065211D01*
G02X55701Y1064946I-1336J3238D01*
G02X52198Y1068449I0J3503D01*
G02X52592Y1070062I3503J-1D01*
G03Y1070247I-177J92D01*
G02X52198Y1071860I3109J1614D01*
G02X52758Y1073760I3503J0D01*
G03Y1073977I-168J108D01*
G37*
G36*
G01X58744Y1092278D02*
G02X59138Y1090665I-3109J-1614D01*
G02X52132I-3503J0D01*
G02X52526Y1092278I3503J-1D01*
G03Y1092463I-177J92D01*
G02X52132Y1094076I3109J1614D01*
G02X59138I3503J0D01*
G02X58744Y1092463I-3503J1D01*
G03Y1092278I177J-92D01*
G37*
G36*
G01X139775Y1093818D02*
G02X139570Y1095000I3297J1181D01*
G02X139775Y1096182I3502J1D01*
G03Y1096318I-188J68D01*
G02X139570Y1097500I3297J1181D01*
G02X146574I3502J0D01*
G02X146369Y1096318I-3502J-1D01*
G03Y1096182I188J-68D01*
G02X146574Y1095000I-3297J-1181D01*
G02X146369Y1093818I-3502J-1D01*
G03Y1093682I188J-68D01*
G02X146574Y1092500I-3297J-1181D01*
G02X139570I-3502J0D01*
G02X139775Y1093682I3502J1D01*
G03Y1093818I-188J68D01*
G37*
G36*
G01X177256Y1105243D02*
G02X176956Y1106662I3202J1418D01*
G02X180458Y1110164I3502J0D01*
G02X181877Y1109864I1J-3502D01*
G03X182039I81J183D01*
G02X183458Y1110164I1418J-3202D01*
G02X184877Y1109864I1J-3502D01*
G03X185039I81J183D01*
G02X186458Y1110164I1418J-3202D01*
G02X189960Y1106662I0J-3502D01*
G02X189660Y1105243I-3502J-1D01*
G03Y1105081I183J-81D01*
G02X189960Y1103662I-3202J-1418D01*
G02X186458Y1100160I-3502J0D01*
G02X185039Y1100460I-1J3502D01*
G03X184877I-81J-183D01*
G02X183458Y1100160I-1418J3202D01*
G02X182039Y1100460I-1J3502D01*
G03X181877I-81J-183D01*
G02X180458Y1100160I-1418J3202D01*
G02X176956Y1103662I0J3502D01*
G02X177256Y1105081I3502J1D01*
G03Y1105243I-183J81D01*
G37*
G36*
G01X15798Y1105881D02*
G02X15498Y1107300I3202J1418D01*
G02X19000Y1110802I3502J0D01*
G02X20419Y1110502I1J-3502D01*
G03X20581I81J183D01*
G02X22000Y1110802I1418J-3202D01*
G02X23419Y1110502I1J-3502D01*
G03X23581I81J183D01*
G02X25000Y1110802I1418J-3202D01*
G02X28502Y1107300I0J-3502D01*
G02X28202Y1105881I-3502J-1D01*
G03Y1105719I183J-81D01*
G02X28502Y1104300I-3202J-1418D01*
G02X25000Y1100798I-3502J0D01*
G02X23581Y1101098I-1J3502D01*
G03X23419I-81J-183D01*
G02X22000Y1100798I-1418J3202D01*
G02X20581Y1101098I-1J3502D01*
G03X20419I-81J-183D01*
G02X19000Y1100798I-1418J3202D01*
G02X15498Y1104300I0J3502D01*
G02X15798Y1105719I3502J1D01*
G03Y1105881I-183J81D01*
G37*
G36*
G01X78002Y1137166D02*
G02X79500Y1137502I1497J-3166D01*
G02X83002Y1134000I0J-3502D01*
G02X79639Y1130500I-3503J0D01*
G03X79562Y1130481I8J-200D01*
G02X78075Y1130150I-1486J3169D01*
G02X74575Y1133650I0J3500D01*
G02X77925Y1137147I3500J0D01*
G03X78002Y1137166I-8J200D01*
G37*
G36*
G01X124559Y1140913D02*
G02X126500Y1141500I1940J-2913D01*
G02Y1134500I0J-3500D01*
G02X125609Y1134615I-1J3500D01*
G03X125447Y1134588I-51J-193D01*
G02X123500Y1133998I-1945J2912D01*
G02Y1141002I0J3502D01*
G02X124397Y1140886I3J-3502D01*
G03X124559Y1140913I51J193D01*
G37*
G36*
G01X124544Y1184158D02*
G02X127760Y1180670I-284J-3488D01*
G02X124260Y1177170I-3500J0D01*
G02X122797Y1177490I-1J3500D01*
G03X122729Y1177508I-84J-181D01*
G02X119498Y1181000I272J3492D01*
G02X123000Y1184502I3502J0D01*
G02X124476Y1184176I0J-3502D01*
G03X124544Y1184158I84J182D01*
G37*
G36*
G01X72934Y1188604D02*
G02X76400Y1191602I3466J-505D01*
G02X79902Y1188100I0J-3502D01*
G02X78177Y1185082I-3503J0D01*
G03X78081Y1184939I102J-172D01*
G02X74618Y1181947I-3463J508D01*
G02X71118Y1185447I0J3500D01*
G02X72838Y1188460I3499J0D01*
G03X72934Y1188604I-102J172D01*
G37*
G36*
G01X165362Y216124D02*
G02X165062Y217543I3202J1418D01*
G02X172066I3502J0D01*
G02X171766Y216124I-3502J-1D01*
G03Y215962I183J-81D01*
G02X172066Y214543I-3202J-1418D01*
G02X168564Y211040I-3502J-1D01*
G02X168118Y211069I4J3503D01*
G01X168058Y211077D01*
X167953Y211026D01*
X167701Y210610D01*
X167704Y210493D01*
X167739Y210444D01*
G02X168366Y208443I-2875J-2000D01*
G02X168066Y207024I-3502J-1D01*
G03Y206862I183J-81D01*
G02X168366Y205443I-3202J-1418D01*
G02X167201Y202834I-3502J-1D01*
G01X167168Y202805D01*
X167134Y202726D01*
X167140Y202335D01*
X167177Y202258D01*
X167211Y202230D01*
G02X168466Y199543I-2247J-2686D01*
G02X168166Y198124I-3502J-1D01*
G03Y197962I183J-81D01*
G02X168466Y196543I-3202J-1418D01*
G02X166163Y193252I-3503J0D01*
G01X166102Y193230D01*
X166030Y193124D01*
X166044Y192615D01*
X166122Y192513D01*
X166184Y192494D01*
G02X168666Y189143I-1021J-3351D01*
G02X168366Y187724I-3502J-1D01*
G03Y187562I183J-81D01*
G02X168666Y186143I-3202J-1418D01*
G02X161662I-3502J0D01*
G02X161962Y187562I3502J1D01*
G03Y187724I-183J81D01*
G02X161662Y189143I3202J1418D01*
G02X163965Y192434I3503J0D01*
G01X164026Y192456D01*
X164098Y192562D01*
X164084Y193071D01*
X164006Y193173D01*
X163944Y193192D01*
G02X161462Y196543I1021J3351D01*
G02X161762Y197962I3502J1D01*
G03Y198124I-183J81D01*
G02X161462Y199543I3202J1418D01*
G02X162627Y202152I3502J1D01*
G01X162660Y202181D01*
X162694Y202260D01*
X162688Y202651D01*
X162651Y202728D01*
X162617Y202756D01*
G02X161362Y205443I2247J2686D01*
G02X161662Y206862I3502J1D01*
G03Y207024I-183J81D01*
G02X161362Y208443I3202J1418D01*
G02X164864Y211946I3502J1D01*
G02X165310Y211917I-4J-3503D01*
G01X165370Y211909D01*
X165475Y211960D01*
X165727Y212376D01*
X165724Y212493D01*
X165689Y212542D01*
G02X165062Y214543I2875J2000D01*
G02X165362Y215962I3502J1D01*
G03Y216124I-183J81D01*
G37*
G36*
G01X28109Y238390D02*
G02X29291Y238596I1184J-3297D01*
G02X30511Y238376I-2J-3503D01*
G03X30651I70J188D01*
G02X31871Y238596I1222J-3283D01*
G02X35374Y235093I0J-3503D01*
G02X35168Y233911I-3503J2D01*
G03Y233775I188J-68D01*
G02X35374Y232593I-3297J-1184D01*
G02X31871Y229090I-3503J0D01*
G02X30670Y229303I2J3503D01*
G03X30532I-69J-188D01*
G02X29331Y229090I-1203J3290D01*
G02X28130Y229303I2J3503D01*
G03X27992I-69J-188D01*
G02X26791Y229090I-1203J3290D01*
G02X23721Y230907I0J3502D01*
G01X23692Y230959D01*
X23587Y231015D01*
X23103Y230971D01*
X23010Y230897D01*
X22991Y230840D01*
G02X22964Y230762I-3323J1107D01*
G03Y230626I188J-68D01*
G02X23170Y229444I-3297J-1184D01*
G02X19667Y225942I-3503J1D01*
G02X18466Y226154I-1J3502D01*
G03X18328I-69J-188D01*
G02X17127Y225942I-1200J3290D01*
G02X15926Y226154I-1J3502D01*
G03X15788I-69J-188D01*
G02X14587Y225942I-1200J3290D01*
G02X11084Y229444I-1J3502D01*
G02X11290Y230626I3503J-2D01*
G03Y230762I-188J68D01*
G02X11084Y231944I3297J1184D01*
G02X14587Y235446I3503J-1D01*
G02X15769Y235241I1J-3502D01*
G03X15905I68J188D01*
G02X17087Y235446I1181J-3297D01*
G02X18307Y235227I1J-3502D01*
G03X18447I70J188D01*
G02X19667Y235446I1219J-3283D01*
G02X22737Y233630I0J-3503D01*
G01X22766Y233578D01*
X22871Y233522D01*
X23355Y233566D01*
X23448Y233640D01*
X23467Y233697D01*
G02X23494Y233775I3323J-1107D01*
G03Y233911I-188J68D01*
G02X23288Y235093I3297J1184D01*
G02X26791Y238596I3503J0D01*
G02X27973Y238390I-2J-3503D01*
G03X28109I68J188D01*
G37*
G36*
G01X151800D02*
G02X152982Y238596I1184J-3297D01*
G02X154202Y238376I-2J-3503D01*
G03X154342I70J188D01*
G02X155562Y238596I1222J-3283D01*
G02X159064Y235093I-1J-3503D01*
G02X158859Y233911I-3502J-1D01*
G03Y233775I188J-68D01*
G02X159064Y232593I-3297J-1181D01*
G02X155562Y229090I-3502J-1D01*
G02X154361Y229303I2J3503D01*
G03X154223I-69J-188D01*
G02X153022Y229090I-1203J3290D01*
G02X151821Y229303I2J3503D01*
G03X151683I-69J-188D01*
G02X150482Y229090I-1203J3290D01*
G02X147412Y230907I0J3502D01*
G01X147383Y230959D01*
X147278Y231015D01*
X146794Y230971D01*
X146701Y230897D01*
X146682Y230840D01*
G02X146655Y230762I-3323J1107D01*
G03Y230626I188J-68D01*
G02X146860Y229444I-3297J-1181D01*
G02X143358Y225942I-3502J0D01*
G02X142157Y226154I-1J3502D01*
G03X142019I-69J-188D01*
G02X140818Y225942I-1200J3290D01*
G02X139598Y226161I-1J3502D01*
G03X139458I-70J-188D01*
G02X138238Y225942I-1219J3283D01*
G02X134736Y229444I0J3502D01*
G02X134923Y230574I3502J1D01*
G03X134921Y230709I-189J65D01*
G02X134696Y231944I3277J1235D01*
G02X138198Y235446I3502J0D01*
G02X139418Y235227I1J-3502D01*
G03X139558I70J188D01*
G02X140778Y235446I1219J-3283D01*
G02X141998Y235227I1J-3502D01*
G03X142138I70J188D01*
G02X143358Y235446I1219J-3283D01*
G02X146428Y233630I0J-3503D01*
G01X146457Y233578D01*
X146562Y233522D01*
X147046Y233566D01*
X147139Y233640D01*
X147158Y233697D01*
G02X147185Y233775I3323J-1107D01*
G03Y233911I-188J68D01*
G02X146980Y235093I3297J1181D01*
G02X150482Y238596I3502J1D01*
G02X151664Y238390I-2J-3503D01*
G03X151800I68J188D01*
G37*
G36*
G01X61024Y320302D02*
G02X62225Y320514I1200J-3290D01*
G02X63426Y320302I1J-3502D01*
G03X63564I69J188D01*
G02X64765Y320514I1200J-3290D01*
G02X68268Y317012I1J-3502D01*
G02X68062Y315830I-3503J2D01*
G03Y315694I188J-68D01*
G02X68268Y314512I-3297J-1184D01*
G02X64765Y311010I-3503J1D01*
G02X63583Y311215I-1J3502D01*
G03X63447I-68J-188D01*
G02X62265Y311010I-1181J3297D01*
G02X61045Y311229I-1J3502D01*
G03X60905I-70J-188D01*
G02X59685Y311010I-1219J3283D01*
G02X56615Y312826I0J3503D01*
G01X56586Y312878D01*
X56481Y312934D01*
X55997Y312890D01*
X55904Y312816D01*
X55885Y312759D01*
G02X55858Y312681I-3323J1107D01*
G03Y312545I188J-68D01*
G02X56064Y311363I-3297J-1184D01*
G02X52561Y307860I-3503J0D01*
G02X51379Y308066I2J3503D01*
G03X51243I-68J-188D01*
G02X50061Y307860I-1184J3297D01*
G02X48841Y308080I2J3503D01*
G03X48701I-70J-188D01*
G02X47481Y307860I-1222J3283D01*
G02X43978Y311363I0J3503D01*
G02X44184Y312545I3503J-2D01*
G03Y312681I-188J68D01*
G02X43978Y313863I3297J1184D01*
G02X47481Y317366I3503J0D01*
G02X48682Y317153I-2J-3503D01*
G03X48820I69J188D01*
G02X50021Y317366I1203J-3290D01*
G02X51222Y317153I-2J-3503D01*
G03X51360I69J188D01*
G02X52561Y317366I1203J-3290D01*
G02X55631Y315549I0J-3502D01*
G01X55660Y315497D01*
X55765Y315441D01*
X56249Y315485D01*
X56342Y315559D01*
X56361Y315616D01*
G02X56388Y315694I3323J-1107D01*
G03Y315830I-188J68D01*
G02X56182Y317012I3297J1184D01*
G02X59685Y320514I3503J-1D01*
G02X60886Y320302I1J-3502D01*
G03X61024I69J188D01*
G37*
G36*
G01X170321D02*
G02X171522Y320514I1200J-3290D01*
G02X172723Y320302I1J-3502D01*
G03X172861I69J188D01*
G02X174062Y320514I1200J-3290D01*
G02X177564Y317012I0J-3502D01*
G02X177359Y315830I-3502J-1D01*
G03Y315694I188J-68D01*
G02X177564Y314512I-3297J-1181D01*
G02X174062Y311010I-3502J0D01*
G02X172880Y311215I-1J3502D01*
G03X172744I-68J-188D01*
G02X171562Y311010I-1181J3297D01*
G02X170342Y311229I-1J3502D01*
G03X170202I-70J-188D01*
G02X168982Y311010I-1219J3283D01*
G02X165912Y312826I0J3503D01*
G01X165883Y312878D01*
X165778Y312934D01*
X165294Y312890D01*
X165201Y312816D01*
X165182Y312759D01*
G02X165155Y312681I-3323J1107D01*
G03Y312545I188J-68D01*
G02X165360Y311363I-3297J-1181D01*
G02X161858Y307860I-3502J-1D01*
G02X160676Y308066I2J3503D01*
G03X160540I-68J-188D01*
G02X159358Y307860I-1184J3297D01*
G02X158138Y308080I2J3503D01*
G03X157998I-70J-188D01*
G02X156778Y307860I-1222J3283D01*
G02X153276Y311363I1J3503D01*
G02X153481Y312545I3502J1D01*
G03Y312681I-188J68D01*
G02X153276Y313863I3297J1181D01*
G02X156778Y317366I3502J1D01*
G02X157979Y317153I-2J-3503D01*
G03X158117I69J188D01*
G02X159318Y317366I1203J-3290D01*
G02X160519Y317153I-2J-3503D01*
G03X160657I69J188D01*
G02X161858Y317366I1203J-3290D01*
G02X164928Y315549I0J-3502D01*
G01X164957Y315497D01*
X165062Y315441D01*
X165546Y315485D01*
X165639Y315559D01*
X165658Y315616D01*
G02X165685Y315694I3323J-1107D01*
G03Y315830I-188J68D01*
G02X165480Y317012I3297J1181D01*
G02X168982Y320514I3502J0D01*
G02X170183Y320302I1J-3502D01*
G03X170321I69J188D01*
G37*
G36*
G01X29423Y926822D02*
G02X29122Y928241I3202J1421D01*
G02X36128I3503J0D01*
G02X35827Y926822I-3503J2D01*
G03Y926660I183J-81D01*
G02X36128Y925241I-3202J-1421D01*
G02X33824Y921950I-3502J0D01*
G01X33763Y921928D01*
X33691Y921822D01*
X33705Y921313D01*
X33783Y921211D01*
X33845Y921192D01*
G02X36328Y917841I-1020J-3351D01*
G02X36027Y916422I-3503J2D01*
G03Y916260I183J-81D01*
G02X36328Y914841I-3202J-1421D01*
G02X29322I-3503J0D01*
G02X29623Y916260I3503J-2D01*
G03Y916422I-183J81D01*
G02X29322Y917841I3202J1421D01*
G02X31626Y921132I3502J0D01*
G01X31687Y921154D01*
X31759Y921260D01*
X31745Y921769D01*
X31667Y921871D01*
X31605Y921890D01*
G02X29122Y925241I1020J3351D01*
G02X29423Y926660I3503J-2D01*
G03Y926822I-183J81D01*
G37*
G36*
G01X45434Y973625D02*
G02X45228Y974807I3297J1184D01*
G02X52234I3503J0D01*
G02X52028Y973625I-3503J2D01*
G03Y973489I188J-68D01*
G02X52234Y972307I-3297J-1184D01*
G02X51960Y970951I-3503J2D01*
G03X51955Y970811I185J-77D01*
G02X52134Y969707I-3324J-1105D01*
G02X51928Y968525I-3503J2D01*
G03Y968389I188J-68D01*
G02X52134Y967207I-3297J-1184D01*
G02X51911Y965977I-3504J0D01*
G03Y965837I187J-70D01*
G02X52134Y964607I-3281J-1230D01*
G02X51928Y963425I-3503J2D01*
G03Y963289I188J-68D01*
G02X52134Y962107I-3297J-1184D01*
G02X51955Y961003I-3503J1D01*
G03X51960Y960863I190J-63D01*
G02X52234Y959507I-3229J-1358D01*
G02X52028Y958325I-3503J2D01*
G03Y958189I188J-68D01*
G02X52234Y957007I-3297J-1184D01*
G02X48731Y953504I-3503J0D01*
G02X45414Y955882I0J3502D01*
G01X45397Y955933D01*
X45319Y956002D01*
X44877Y956096D01*
X44778Y956065D01*
X44741Y956025D01*
G02X42167Y954898I-2574J2376D01*
G02X40748Y955198I-1J3502D01*
G03X40586I-81J-183D01*
G02X39167Y954898I-1418J3202D01*
G02X35740Y957677I0J3503D01*
G01X35727Y957740D01*
X35634Y957825D01*
X35133Y957892D01*
X35021Y957833D01*
X34992Y957776D01*
G02X31871Y955862I-3122J1589D01*
G02X30670Y956075I2J3503D01*
G03X30532I-69J-188D01*
G02X29331Y955862I-1203J3290D01*
G02X28130Y956075I2J3503D01*
G03X27992I-69J-188D01*
G02X26791Y955862I-1203J3290D01*
G02X23721Y957679I0J3502D01*
G01X23692Y957731D01*
X23587Y957787D01*
X23103Y957743D01*
X23010Y957669D01*
X22991Y957612D01*
G02X22964Y957534I-3323J1107D01*
G03Y957398I188J-68D01*
G02X23170Y956216I-3297J-1184D01*
G02X19667Y952714I-3503J1D01*
G02X18466Y952926I-1J3502D01*
G03X18328I-69J-188D01*
G02X17127Y952714I-1200J3290D01*
G02X15926Y952926I-1J3502D01*
G03X15788I-69J-188D01*
G02X14587Y952714I-1200J3290D01*
G02X11084Y956216I-1J3502D01*
G02X11290Y957398I3503J-2D01*
G03Y957534I-188J68D01*
G02X11084Y958716I3297J1184D01*
G02X14587Y962218I3503J-1D01*
G02X15769Y962013I1J-3502D01*
G03X15905I68J188D01*
G02X17087Y962218I1181J-3297D01*
G02X18307Y961999I1J-3502D01*
G03X18447I70J188D01*
G02X19667Y962218I1219J-3283D01*
G02X22737Y960402I0J-3503D01*
G01X22766Y960350D01*
X22871Y960294D01*
X23355Y960338D01*
X23448Y960412D01*
X23467Y960469D01*
G02X23494Y960547I3323J-1107D01*
G03Y960683I-188J68D01*
G02X23288Y961865I3297J1184D01*
G02X26791Y965368I3503J0D01*
G02X27973Y965162I-2J-3503D01*
G03X28109I68J188D01*
G02X29291Y965368I1184J-3297D01*
G02X30511Y965148I-2J-3503D01*
G03X30651I70J188D01*
G02X31871Y965368I1222J-3283D01*
G02X35374Y961865I0J-3503D01*
G02X35168Y960683I-3503J2D01*
G03Y960547I188J-68D01*
G02X35298Y960088I-3297J-1182D01*
G01X35311Y960025D01*
X35404Y959940D01*
X35905Y959873D01*
X36017Y959932D01*
X36046Y959989D01*
G02X39167Y961902I3121J-1589D01*
G02X40586Y961602I1J-3502D01*
G03X40748I81J183D01*
G02X42167Y961902I1418J-3202D01*
G02X44946Y960532I1J-3502D01*
G03X45138Y960457I158J122D01*
G01X45250Y960476D01*
G03X45407Y960610I-33J197D01*
G01Y960611D01*
G03X45402Y960751I-190J63D01*
G02X45128Y962107I3229J1358D01*
G02X45334Y963289I3503J-2D01*
G03Y963425I-188J68D01*
G02X45128Y964607I3297J1184D01*
G02X45351Y965837I3504J0D01*
G03Y965977I-187J70D01*
G02X45128Y967207I3281J1230D01*
G02X45334Y968389I3503J-2D01*
G03Y968525I-188J68D01*
G02X45128Y969707I3297J1184D01*
G02X45402Y971063I3503J-2D01*
G03X45407Y971203I-185J77D01*
G02X45228Y972307I3324J1105D01*
G02X45434Y973489I3503J-2D01*
G03Y973625I-188J68D01*
G37*
G36*
G01X61524Y1047074D02*
G02X62725Y1047286I1200J-3290D01*
G02X63926Y1047074I1J-3502D01*
G03X64064I69J188D01*
G02X65265Y1047286I1200J-3290D01*
G02X68768Y1043784I1J-3502D01*
G02X68562Y1042602I-3503J2D01*
G03Y1042466I188J-68D01*
G02X68768Y1041284I-3297J-1184D01*
G02X65265Y1037782I-3503J1D01*
G02X64083Y1037987I-1J3502D01*
G03X63947I-68J-188D01*
G02X62765Y1037782I-1181J3297D01*
G02X61545Y1038001I-1J3502D01*
G03X61405I-70J-188D01*
G02X60185Y1037782I-1219J3283D01*
G02X57115Y1039598I0J3503D01*
G01X57086Y1039650D01*
X56981Y1039706D01*
X56497Y1039662D01*
X56404Y1039588D01*
X56385Y1039531D01*
G02X56358Y1039453I-3323J1107D01*
G03Y1039317I188J-68D01*
G02X56564Y1038135I-3297J-1184D01*
G02X53061Y1034632I-3503J0D01*
G02X51879Y1034838I2J3503D01*
G03X51743I-68J-188D01*
G02X50561Y1034632I-1184J3297D01*
G02X49341Y1034852I2J3503D01*
G03X49201I-70J-188D01*
G02X47981Y1034632I-1222J3283D01*
G02X44478Y1038135I0J3503D01*
G02X44684Y1039317I3503J-2D01*
G03Y1039453I-188J68D01*
G02X44478Y1040635I3297J1184D01*
G02X47981Y1044138I3503J0D01*
G02X49182Y1043925I-2J-3503D01*
G03X49320I69J188D01*
G02X50521Y1044138I1203J-3290D01*
G02X51722Y1043925I-2J-3503D01*
G03X51860I69J188D01*
G02X53061Y1044138I1203J-3290D01*
G02X56131Y1042321I0J-3502D01*
G01X56160Y1042269D01*
X56265Y1042213D01*
X56749Y1042257D01*
X56842Y1042331D01*
X56861Y1042388D01*
G02X56888Y1042466I3323J-1107D01*
G03Y1042602I-188J68D01*
G02X56682Y1043784I3297J1184D01*
G02X60185Y1047286I3503J-1D01*
G02X61386Y1047074I1J-3502D01*
G03X61524I69J188D01*
G37*
G36*
G01X170321D02*
G02X171522Y1047286I1200J-3290D01*
G02X172723Y1047074I1J-3502D01*
G03X172861I69J188D01*
G02X174062Y1047286I1200J-3290D01*
G02X177564Y1043784I0J-3502D01*
G02X177359Y1042602I-3502J-1D01*
G03Y1042466I188J-68D01*
G02X177564Y1041284I-3297J-1181D01*
G02X174062Y1037782I-3502J0D01*
G02X172880Y1037987I-1J3502D01*
G03X172744I-68J-188D01*
G02X171562Y1037782I-1181J3297D01*
G02X170342Y1038001I-1J3502D01*
G03X170202I-70J-188D01*
G02X168982Y1037782I-1219J3283D01*
G02X165912Y1039598I0J3503D01*
G01X165883Y1039650D01*
X165778Y1039706D01*
X165294Y1039662D01*
X165201Y1039588D01*
X165182Y1039531D01*
G02X165155Y1039453I-3323J1107D01*
G03Y1039317I188J-68D01*
G02X165360Y1038135I-3297J-1181D01*
G02X161858Y1034632I-3502J-1D01*
G02X160676Y1034838I2J3503D01*
G03X160540I-68J-188D01*
G02X159358Y1034632I-1184J3297D01*
G02X158138Y1034852I2J3503D01*
G03X157998I-70J-188D01*
G02X156778Y1034632I-1222J3283D01*
G02X153276Y1038135I1J3503D01*
G02X153481Y1039317I3502J1D01*
G03Y1039453I-188J68D01*
G02X153276Y1040635I3297J1181D01*
G02X156778Y1044138I3502J1D01*
G02X157979Y1043925I-2J-3503D01*
G03X158117I69J188D01*
G02X159318Y1044138I1203J-3290D01*
G02X160519Y1043925I-2J-3503D01*
G03X160657I69J188D01*
G02X161858Y1044138I1203J-3290D01*
G02X164928Y1042321I0J-3502D01*
G01X164957Y1042269D01*
X165062Y1042213D01*
X165546Y1042257D01*
X165639Y1042331D01*
X165658Y1042388D01*
G02X165685Y1042466I3323J-1107D01*
G03Y1042602I-188J68D01*
G02X165480Y1043784I3297J1181D01*
G02X168982Y1047286I3502J0D01*
G02X170183Y1047074I1J-3502D01*
G03X170321I69J188D01*
G37*
G54D37*
X77518Y406378D03*
X67500Y124242D03*
G54D36*
X7500Y44000D03*
X23000Y760000D03*
X13500Y862500D03*
X76000Y133500D03*
X71000Y427000D03*
X70500Y443500D03*
X60000Y797925D03*
X68000Y804606D03*
X75500Y852500D03*
X82500Y398000D03*
X82000Y415000D03*
X84000Y844950D03*
X102500Y979500D03*
X123500Y59500D03*
X107000Y389500D03*
X123000Y829114D03*
X135750Y132750D03*
X127500Y129500D03*
X165500Y1229900D03*
G54D34*
X173228Y474842D03*
X30315Y768150D03*
Y41378D03*
X173228Y1201614D03*
Y111456D03*
X30315Y1131536D03*
X173228Y838228D03*
X30315Y404764D03*
G54D35*
X34252Y80354D03*
X26378Y88228D03*
X34252Y443740D03*
X26378Y451614D03*
X34252Y807126D03*
X26378Y815000D03*
X34252Y1170512D03*
X26378Y1178386D03*
X169291Y72480D03*
Y435866D03*
Y799252D03*
Y1162638D03*
X177165Y64606D03*
Y427992D03*
Y791378D03*
Y1154764D03*
G54D33*
X-58189Y619685D03*
Y1307087D03*
X44000Y17500D03*
X178500D03*
X20000Y1307000D03*
G54D26*
X42717Y595122D03*
X101772Y178779D03*
Y926810D03*
X160827Y595122D03*
G54D17*
X7500Y44000D03*
X9400Y241516D03*
X10500Y274500D03*
X11800Y284000D03*
X12000Y641000D03*
X9838Y994729D03*
X34544Y192540D03*
X34480Y202243D03*
X29191Y210428D03*
Y207428D03*
X22170Y246150D03*
X14791Y247715D03*
X17782Y248150D03*
X29390Y246960D03*
X26040Y245190D03*
X29291Y235093D03*
X26791D03*
X31871D03*
X26791Y232593D03*
X29331D03*
X31871D03*
X14587Y231944D03*
X17087D03*
X19667D03*
Y229444D03*
X17127D03*
X14587D03*
X12791Y261000D03*
X17953Y267500D03*
X21500D03*
X32716Y273500D03*
X24000Y276000D03*
X18185Y312228D03*
X21185D03*
Y315228D03*
X18185D03*
X24185Y312228D03*
X27185D03*
Y315228D03*
X24185D03*
X26500Y358728D03*
X23500D03*
X20500D03*
X17500D03*
Y361728D03*
X26500D03*
X20500D03*
X23500D03*
X11000Y502000D03*
Y511000D03*
X10987Y523418D03*
X20452Y513547D03*
X27580Y528341D03*
X29500Y534075D03*
X28900Y556900D03*
X30380Y648320D03*
X32720Y660000D03*
X32258Y646000D03*
X21000Y644000D03*
X32760Y657000D03*
X21525Y660000D03*
Y654000D03*
X12389Y653509D03*
X12512Y647013D03*
X25023Y663850D03*
X14925Y663000D03*
X21525Y666500D03*
X32760Y669500D03*
X21525Y672500D03*
X32760Y682000D03*
X25023Y669850D03*
X32728Y679000D03*
X12500D03*
X14925Y669000D03*
Y690000D03*
X13000Y709000D03*
X20453Y708047D03*
X15713Y710009D03*
X20327Y711174D03*
X17500Y734000D03*
X13375Y730274D03*
X17500Y741000D03*
Y748000D03*
X12819Y751500D03*
X15012Y745563D03*
X17458Y737184D03*
X12419Y765261D03*
X14830Y763614D03*
X23000Y760000D03*
X13500Y862500D03*
X32525Y904241D03*
Y907241D03*
X32825Y917841D03*
Y914841D03*
X32625Y925241D03*
Y928241D03*
X27587Y937815D03*
Y934815D03*
X31871Y961865D03*
X26791D03*
X29291D03*
X31871Y959365D03*
X29331D03*
X26791D03*
X14587Y958716D03*
X17087D03*
X19667D03*
Y956216D03*
X17127D03*
X14587D03*
X26990Y975034D03*
X14791Y976000D03*
X17500Y974500D03*
X28791Y976919D03*
X27886Y972134D03*
X23702Y992261D03*
X20000Y989000D03*
X23009Y995491D03*
X30522Y1000288D03*
X15000Y1001300D03*
X24685Y1041800D03*
X18185Y1041900D03*
X21385D03*
X24685Y1038800D03*
X21385Y1038900D03*
X18185D03*
X13492Y1049256D03*
Y1051756D03*
Y1046676D03*
X25000Y1104300D03*
X22000D03*
X19000D03*
Y1107300D03*
X22000D03*
X25000D03*
X19500Y1239500D03*
X12150Y1227850D03*
X47399Y149664D03*
X44399D03*
Y152164D03*
X47399D03*
Y146864D03*
X44399D03*
X34380Y179643D03*
X47487Y171264D03*
X44487D03*
Y174264D03*
X47487D03*
X34380Y182643D03*
X34544Y189540D03*
X34480Y199243D03*
X36880Y249217D03*
X42309Y251270D03*
X50967Y246228D03*
X53967D03*
X48477Y233457D03*
X51477D03*
X54477D03*
X39167Y230228D03*
X42167D03*
X51456Y230214D03*
X48456D03*
X54456D03*
X41864Y265636D03*
X38880Y263169D03*
X44500Y272767D03*
X38383Y280119D03*
X40472Y283287D03*
X55650Y280728D03*
X40500Y295500D03*
X53343Y301334D03*
X44500Y301500D03*
X52000Y298528D03*
X57430Y298520D03*
X50021Y313863D03*
X52561D03*
Y311363D03*
X50061D03*
X47481D03*
Y313863D03*
X37185Y316228D03*
X40185D03*
X53000Y345997D03*
Y348497D03*
Y350997D03*
X55700Y342500D03*
X53000Y364997D03*
Y367497D03*
Y369997D03*
X49689Y474203D03*
X56925Y503000D03*
Y528500D03*
Y508500D03*
Y523500D03*
Y518500D03*
X57000Y538500D03*
X47499Y649000D03*
X52977Y662650D03*
X56475Y654000D03*
X46950Y666500D03*
X56475Y672500D03*
X46950D03*
X52977Y681650D03*
X34000Y757000D03*
X37000Y756900D03*
X38900Y800200D03*
X52800Y813500D03*
X47813Y833013D03*
X48308Y877415D03*
Y880415D03*
Y883415D03*
X50808Y877415D03*
Y880415D03*
Y883415D03*
X48631Y964607D03*
Y962107D03*
X48731Y959507D03*
Y957007D03*
X42167Y958400D03*
X39167D03*
X48731Y972307D03*
Y974807D03*
X48631Y969707D03*
Y967207D03*
X35259Y968798D03*
X38500Y977199D03*
X40500Y995000D03*
X39061Y1005000D03*
X40972Y1010059D03*
X38880Y989941D03*
X48492Y1006856D03*
X51852Y1012249D03*
X42000Y1023000D03*
X44100Y1027850D03*
X50000Y1023000D03*
X53000Y1026000D03*
X40585Y1041300D03*
X37585D03*
X50561Y1038135D03*
X53061D03*
Y1040635D03*
X50521D03*
X47981D03*
Y1038135D03*
X55700Y1079289D03*
Y1075878D03*
X55701Y1071860D03*
Y1068449D03*
X55635Y1090665D03*
Y1094076D03*
X40500Y1164000D03*
X68416Y63842D03*
X60475Y79692D03*
X61000Y84192D03*
X68500Y70000D03*
X64025Y92575D03*
X65350Y102000D03*
X76000Y133500D03*
X71500Y130000D03*
X76743Y116500D03*
X56967Y246228D03*
X72500Y283771D03*
X64500Y287000D03*
X58561Y280728D03*
X66561Y273985D03*
X71689Y302000D03*
X64561Y298446D03*
X61420Y299310D03*
X64765Y314512D03*
Y317012D03*
X62265Y314512D03*
X62225Y317012D03*
X59685D03*
Y314512D03*
X78500Y406000D03*
X65900Y413000D03*
X60475Y424728D03*
Y429228D03*
X67000Y430500D03*
X71000Y427000D03*
X58500Y454500D03*
X79500Y449925D03*
X58500Y441000D03*
X65350Y447500D03*
X70500Y443500D03*
X68000Y463878D03*
X71300Y460000D03*
X57000Y483000D03*
X56925Y498000D03*
Y493000D03*
Y488000D03*
Y513500D03*
X79293Y523513D03*
X75650Y517770D03*
X56925Y533500D03*
X68345Y533265D03*
X76500Y531476D03*
X72500Y541500D03*
X75396Y544500D03*
X73747Y570715D03*
X74000Y608425D03*
X56475Y641000D03*
X78457Y634010D03*
X78677Y637315D03*
X63070Y652400D03*
X56475Y647000D03*
Y660000D03*
X68000Y664000D03*
X56475Y666500D03*
Y679000D03*
Y685000D03*
X69000Y669745D03*
X68000Y676500D03*
X59475Y688975D03*
X76500Y704000D03*
Y709500D03*
X60000Y696984D03*
X69350Y711940D03*
X68100Y721000D03*
X61500Y728500D03*
X70925Y732000D03*
X76475Y715000D03*
X65570Y734500D03*
X74075Y721500D03*
Y726500D03*
X76475Y742500D03*
X70925Y749000D03*
X58612Y740500D03*
X76725Y749500D03*
X66000Y776000D03*
X61576Y762200D03*
X69000Y771500D03*
X77400Y775000D03*
X62058Y801075D03*
X60000Y797925D03*
X71500Y805500D03*
X77000Y819000D03*
X67993Y827764D03*
X65350Y818654D03*
X77000Y823500D03*
X68000Y804606D03*
X71410Y846500D03*
X75500Y852500D03*
X73000Y1010500D03*
X56150Y1007500D03*
X72000Y1013500D03*
X59268Y1007793D03*
X69802Y1006198D03*
X74000Y1026000D03*
X66000Y1025000D03*
X62500Y1025500D03*
X60185Y1043784D03*
X62725D03*
X65265D03*
Y1041284D03*
X62765D03*
X60185D03*
X61029Y1064153D03*
Y1060742D03*
X64231Y1115268D03*
X77518Y1138500D03*
X68686Y1139993D03*
X76500Y1162975D03*
X60475Y1152000D03*
X61500Y1160000D03*
X79000Y1157425D03*
Y1173425D03*
X64425Y1165500D03*
X64843Y1194000D03*
X79106Y1176575D03*
X75000Y1196500D03*
X64850Y1179000D03*
X76400Y1188100D03*
X82975Y53333D03*
X84400Y64200D03*
X99000Y61000D03*
X99883Y57500D03*
X87500Y83300D03*
X79500Y86925D03*
X80500Y74000D03*
X88802Y100198D03*
X86000Y92000D03*
X94430Y103830D03*
X79500Y104425D03*
X88900Y119300D03*
X82500Y389500D03*
Y398000D03*
X79463Y429962D03*
X91500Y434000D03*
X82000Y415000D03*
X100835Y446500D03*
X91593Y439000D03*
X95000Y462740D03*
X96502Y501930D03*
X84575Y487075D03*
X95184Y493787D03*
X98040Y506730D03*
X87500Y522800D03*
X98925Y515000D03*
X96275Y519750D03*
X98925Y534000D03*
X82000Y531476D03*
X87500D03*
X93000D03*
X84723Y532202D03*
X102075Y534000D03*
X84050Y555925D03*
X85000Y562148D03*
X100505Y561919D03*
X97000Y569153D03*
X90680Y561766D03*
X98780Y617000D03*
X99051Y635051D03*
X87500Y634700D03*
X88300Y639800D03*
X103037Y624462D03*
X91532Y663261D03*
X95032Y660000D03*
X86000Y676000D03*
Y684000D03*
X101284Y671500D03*
X101309Y675500D03*
X86000Y700000D03*
X79975Y739975D03*
X99279Y781942D03*
X99500Y787000D03*
X83000Y804000D03*
X94000Y825740D03*
Y818500D03*
X101500Y824271D03*
X83000Y810000D03*
X84000Y844950D03*
X99000Y848000D03*
X104500Y834500D03*
X80000Y828500D03*
X102500Y979500D03*
X79500Y1134000D03*
X91000Y1173425D03*
X81000Y1193425D03*
X86000Y1176575D03*
X111522Y39800D03*
X114522D03*
X111522Y44800D03*
X114522D03*
X111522Y47300D03*
Y49800D03*
X114522D03*
Y52300D03*
X111522D03*
X114522Y47300D03*
X111522Y42300D03*
X114522D03*
X123500Y59500D03*
X118475Y83500D03*
X115918Y75650D03*
X112000Y88700D03*
X122500Y102000D03*
X123500Y115500D03*
X103000Y136500D03*
X127482Y312228D03*
X107000Y389500D03*
Y400425D03*
X118500Y403500D03*
X107966Y408260D03*
X110000Y392500D03*
X117500Y398500D03*
X110500Y445000D03*
X106850Y441596D03*
X104500Y478500D03*
X122000Y463000D03*
X118490Y495330D03*
X124500Y485000D03*
X119000D03*
X113500D03*
X109000Y500000D03*
X105760Y493500D03*
X104500Y483425D03*
X126070Y493931D03*
X112070Y499790D03*
X109000Y485000D03*
X113500Y523000D03*
X111000Y506000D03*
X108500Y512000D03*
X108000Y539500D03*
X109000Y543500D03*
X111000Y555925D03*
X115788Y573787D03*
X125000Y562500D03*
X106977Y561919D03*
X121500Y557500D03*
X120000Y581500D03*
X108601Y627084D03*
X118079Y639954D03*
X106000Y634500D03*
X124499Y660000D03*
X126185Y688915D03*
X123401Y669102D03*
X117500Y689900D03*
X119500Y707500D03*
X118000Y696000D03*
X119500Y715500D03*
X115525Y731000D03*
X119000Y734000D03*
X125075Y715000D03*
X115525Y745000D03*
Y738000D03*
X112294Y754294D03*
X125352Y749277D03*
X114857Y741500D03*
X121536Y749253D03*
X121841Y775967D03*
X119836Y761664D03*
X125654Y772281D03*
X107365Y776004D03*
X118711Y797500D03*
X120500Y845000D03*
X123000Y829114D03*
X117500Y857575D03*
X119500Y992000D03*
X127182Y1039000D03*
X110000Y1128425D03*
X121000Y1131575D03*
X124500Y1148575D03*
X109500Y1139500D03*
X123500Y1137500D03*
X118000Y1151575D03*
X123000Y1181000D03*
X127000Y77500D03*
X142000Y74575D03*
X132350Y94273D03*
X142500Y103342D03*
X142000Y98842D03*
X138650Y94000D03*
X132500Y99000D03*
X135000Y120500D03*
X137449Y113340D03*
X135750Y132750D03*
X127500Y129500D03*
X141890Y246451D03*
X128000Y251000D03*
X137495Y248875D03*
X138198Y231944D03*
X140778D03*
X143358D03*
Y229444D03*
X140818D03*
X138238D03*
X133529Y265385D03*
X147393Y265728D03*
X136500Y261000D03*
X144482Y265728D03*
X142400Y269800D03*
X147500Y278228D03*
X136482Y272471D03*
X133482Y315228D03*
Y312228D03*
X130482Y315228D03*
Y312228D03*
X146482Y316228D03*
X127482Y315228D03*
X144600Y337100D03*
Y339828D03*
X135245Y407228D03*
X132850Y421837D03*
X130500Y432500D03*
X139150Y420193D03*
Y429650D03*
X135000Y463000D03*
X129000Y468000D03*
X135500Y485024D03*
X130000Y485025D03*
X148000Y483000D03*
X150575Y504500D03*
X144324Y498325D03*
X145193Y504232D03*
X141500Y516500D03*
X144335Y509166D03*
X138532Y507500D03*
X150575Y534500D03*
X128500Y554925D03*
X135500Y562500D03*
X133491Y560490D03*
X131500Y634500D03*
X135000Y637500D03*
X150300Y645900D03*
X141900Y645410D03*
X128000Y694500D03*
X133575Y692000D03*
X139150Y712500D03*
X136500Y728500D03*
X128065Y725566D03*
X136500Y742000D03*
X133900Y776000D03*
X129285Y781799D03*
X128500Y791500D03*
X132370Y788872D03*
X128500Y786500D03*
X139650Y785905D03*
X139075Y801984D03*
X134800Y826614D03*
X138428Y806903D03*
X141088Y804709D03*
X133246Y811300D03*
X142999Y842350D03*
X148281Y838882D03*
X145600Y838100D03*
X146000Y854500D03*
X138278Y961865D03*
X140778D03*
X143358D03*
Y959365D03*
X140818D03*
X138278D03*
X129112Y978769D03*
X142000Y977500D03*
X138605Y977649D03*
X146644Y1007363D03*
X133529Y995306D03*
X136482Y1002392D03*
X147393Y995649D03*
X147229Y1004299D03*
X139435Y989500D03*
X144482Y995649D03*
X149500Y1023000D03*
X127182Y1055000D03*
Y1042000D03*
X133382Y1055000D03*
Y1042000D03*
Y1039000D03*
X130382Y1055000D03*
Y1042000D03*
Y1039000D03*
X146482Y1043000D03*
X143072Y1073000D03*
Y1075500D03*
Y1078000D03*
X141572Y1067900D03*
Y1070400D03*
X143072Y1092500D03*
Y1095000D03*
Y1097500D03*
X132175Y1117325D03*
X127000Y1143000D03*
X135800Y1138000D03*
X138650Y1149500D03*
X127000Y1157025D03*
Y1166000D03*
X142500Y1161500D03*
X138650Y1165500D03*
X126360Y1185947D03*
X136800Y1194800D03*
X142500Y1176000D03*
X148576Y146649D03*
X151576D03*
Y149149D03*
X148576D03*
X154576Y146649D03*
Y149149D03*
X149664Y174443D03*
Y171443D03*
Y168443D03*
Y165443D03*
X165164Y186143D03*
Y189143D03*
X164964Y199543D03*
Y196543D03*
X164864Y208443D03*
Y205443D03*
X168564Y217543D03*
Y214543D03*
X150500Y247000D03*
X153022Y232593D03*
X150482D03*
X155562D03*
X165562Y230593D03*
X163022D03*
X150482Y235093D03*
X152982D03*
X155562D03*
X152500Y249501D03*
X161200Y251200D03*
X159430Y244830D03*
X165014Y268287D03*
X161105Y266081D03*
X149769Y283287D03*
X164947Y280728D03*
X152420Y296500D03*
X167000Y296310D03*
X169358Y286228D03*
X167858Y279310D03*
X160777Y275688D03*
X149500Y295500D03*
X160000Y298500D03*
X170358Y298858D03*
X156778Y311363D03*
Y313863D03*
X159318D03*
X161858D03*
Y311363D03*
X159358D03*
X149482Y316228D03*
X162783Y301463D03*
X168982Y314512D03*
X171562D03*
X171522Y317012D03*
X168982D03*
X158858Y329228D03*
Y332228D03*
X149900Y346300D03*
Y349028D03*
Y351800D03*
Y364300D03*
Y370300D03*
Y367528D03*
X151635Y476202D03*
X154000Y471000D03*
X150575Y494500D03*
Y499500D03*
X150500Y489500D03*
X150575Y524500D03*
Y519500D03*
Y509500D03*
X153725Y524500D03*
Y514500D03*
X169000Y535075D03*
X150500Y544500D03*
X150575Y539500D03*
Y529500D03*
X167190Y529510D03*
X171977Y656850D03*
X166547Y663500D03*
X159051Y671661D03*
X167679Y674254D03*
X167642Y682217D03*
X169475Y706000D03*
X167060Y692500D03*
X171440Y708767D03*
X169475Y733000D03*
Y713000D03*
Y720000D03*
X171586Y735683D03*
X171580Y716500D03*
X163925Y756500D03*
X169475Y747000D03*
Y740000D03*
X171500Y743500D03*
X172000Y751500D03*
X149000Y854500D03*
X152364Y890115D03*
Y893115D03*
Y896115D03*
X149864Y890115D03*
Y893115D03*
Y896115D03*
X162877Y910500D03*
Y913500D03*
Y931500D03*
Y934500D03*
Y921500D03*
Y924500D03*
X168177Y940100D03*
X153622Y962514D03*
X151082D03*
Y965014D03*
X153582D03*
X156162D03*
Y962514D03*
X167858Y961800D03*
X164858D03*
X168177Y943100D03*
X149658Y974968D03*
X159000Y972500D03*
X152823Y978573D03*
X160732Y977966D03*
X164600Y998649D03*
X161581Y995673D03*
X149769Y1010059D03*
X164947Y1007500D03*
X167858D03*
X164337Y1002475D03*
X169358Y1013000D03*
X161884Y1026048D03*
X170929Y1024429D03*
X159500Y1023000D03*
X153150Y1028430D03*
X149482Y1043000D03*
X156778Y1038135D03*
Y1040635D03*
X159318D03*
X161858D03*
Y1038135D03*
X159358D03*
X168982Y1043784D03*
X171522D03*
X171562Y1041284D03*
X168982D03*
X164000Y1171500D03*
X165500Y1229900D03*
X179358Y230328D03*
Y227328D03*
X182358Y230328D03*
X185358D03*
X182358Y227328D03*
X185358D03*
X185658Y243528D03*
X182658D03*
X179658D03*
X178811Y281071D03*
X175858Y273985D03*
X173858Y298500D03*
X183500Y299500D03*
X174062Y314512D03*
Y317012D03*
X176858Y359790D03*
Y362290D03*
X185858Y359790D03*
X182858D03*
Y362290D03*
X185858D03*
X179858Y359790D03*
Y362290D03*
X189500Y512000D03*
X191575Y524000D03*
X188516Y518310D03*
X179000Y531925D03*
X189250Y541750D03*
X191991Y536336D03*
X194000Y550000D03*
X191500Y529500D03*
X191259Y547500D03*
X182500Y641600D03*
X187500Y643500D03*
X176000Y659500D03*
X175500Y651500D03*
X180500Y684500D03*
X182500Y688000D03*
X177500Y679500D03*
X175500Y672500D03*
X175475Y668500D03*
X179000Y676500D03*
X187925Y701000D03*
X181000Y696500D03*
X179000Y694000D03*
X190300Y725200D03*
X187041Y730000D03*
X193000Y754500D03*
X191000Y756500D03*
X184425Y738000D03*
X189000Y758500D03*
X173200Y770800D03*
X180658Y956100D03*
X186658D03*
Y952900D03*
X180658D03*
X183758Y956200D03*
Y953000D03*
X180658Y969000D03*
X186658D03*
X183758Y969100D03*
X178811Y1007843D03*
X175858Y1000757D03*
X182058Y1022519D03*
X173858Y1025500D03*
X174062Y1043784D03*
Y1041284D03*
X186458Y1103662D03*
X183458D03*
X180458D03*
X186458Y1106662D03*
X180458D03*
X183458D03*
X192000Y1240500D03*
X182600Y1228850D03*
X195000Y752500D03*
G54D27*
X42717Y620713D03*
X101772Y204370D03*
Y952401D03*
X160827Y620713D03*
G54D24*
X14791Y210028D03*
Y207028D03*
X25545Y248578D03*
X27912Y270676D03*
X32000Y261000D03*
X10000Y267303D03*
X11700Y907753D03*
Y904753D03*
Y918753D03*
Y915753D03*
X12053Y937268D03*
Y934268D03*
X11700Y928753D03*
Y925753D03*
X25500Y977500D03*
X31791Y993000D03*
X26500Y997500D03*
X15275Y995500D03*
X39167Y244728D03*
X42167D03*
X55167Y259228D03*
X52167D03*
X55167Y272228D03*
Y256328D03*
X52167D03*
X45500Y646000D03*
X45240Y657000D03*
Y669500D03*
Y682000D03*
X42367Y972800D03*
X39367D03*
X61300Y66900D03*
X69100Y76100D03*
X71650Y94259D03*
Y111259D03*
X62716Y129542D03*
X75500Y130000D03*
X58167Y259228D03*
X61167D03*
X58167Y272228D03*
X61167D03*
X64167D03*
X58167Y256328D03*
X61167D03*
X68700Y400000D03*
X78500Y410000D03*
X62216Y412678D03*
X69018Y420378D03*
X74979Y437559D03*
X65250Y470378D03*
X65475Y666500D03*
X65500Y671500D03*
X65475Y685000D03*
Y679000D03*
X58673Y775800D03*
X77816Y764764D03*
X78000Y782500D03*
X68694Y764764D03*
X68481Y800951D03*
X69018Y783764D03*
X62216Y830875D03*
X77018Y836764D03*
X65367Y996400D03*
X62367D03*
X56367D03*
X59367D03*
X62216Y1139950D03*
X77518Y1142650D03*
X68543Y1128650D03*
X77816D03*
X69018Y1147650D03*
X71150Y1165500D03*
X74313Y1178559D03*
X73505Y1200075D03*
X84500Y404000D03*
X139435Y266728D03*
X145982Y268287D03*
X139435Y996649D03*
X145982Y998208D03*
X165858Y244728D03*
X162858D03*
X155482Y266228D03*
X149000Y250000D03*
X156962Y692037D03*
X164758Y976500D03*
X167758D03*
X151000Y981000D03*
X155482Y996149D03*
X183582Y217228D03*
Y214228D03*
X181258Y269528D03*
X184258D03*
X187258D03*
X178258D03*
X181067Y256528D03*
X184067D03*
X187067D03*
X178067D03*
X180967Y253728D03*
X177967D03*
X183967D03*
X186967D03*
X187050Y652000D03*
Y659500D03*
Y663500D03*
X184377Y910500D03*
Y913500D03*
X183177Y940100D03*
X184377Y931500D03*
Y934500D03*
Y921500D03*
Y924500D03*
X183177Y943100D03*
X187658Y995000D03*
Y998000D03*
X184658Y995000D03*
Y998000D03*
X181658Y995000D03*
Y998000D03*
X190158Y995000D03*
Y998000D03*
G54D29*
X73300Y340600D03*
Y338100D03*
X74700Y346000D03*
Y351000D03*
Y348500D03*
X74428Y370500D03*
Y368000D03*
Y365500D03*
X76526Y1075845D03*
X76464Y1079181D03*
Y1072947D03*
X76526Y1069611D03*
X75860Y1064323D03*
X75893Y1061138D03*
X76431Y1094565D03*
X76493Y1091229D03*
X112500Y76000D03*
X113000Y394500D03*
X112441Y418434D03*
X107500Y782530D03*
X121072Y1077500D03*
Y1075000D03*
Y1072500D03*
Y1094500D03*
Y1092000D03*
Y1097000D03*
X121000Y1128425D03*
X112941Y1146240D03*
X130200Y339900D03*
Y337400D03*
X126760Y1071023D03*
X126793Y1067838D03*
G54D23*
X13080Y179343D03*
Y182343D03*
Y192843D03*
Y189843D03*
X13580Y201643D03*
Y198643D03*
G54D25*
X18000Y491500D03*
X20500Y497500D03*
Y495000D03*
G54D21*
X34252Y64606D03*
Y56732D03*
Y48858D03*
X26378Y64606D03*
Y56732D03*
Y48858D03*
X34252Y88228D03*
Y80354D03*
X26378Y88228D03*
Y72480D03*
X34252Y103976D03*
Y96102D03*
X26378Y103976D03*
Y96102D03*
X34252Y412244D03*
X26378D03*
X34252Y427992D03*
Y420118D03*
X26378Y435866D03*
Y427992D03*
Y420118D03*
X34252Y451614D03*
Y443740D03*
X26378Y451614D03*
X34252Y467362D03*
Y459488D03*
X26378Y467362D03*
Y459488D03*
X34252Y775630D03*
X26378D03*
X34252Y791378D03*
Y783504D03*
X26378Y799252D03*
Y791378D03*
Y783504D03*
X34252Y822874D03*
Y815000D03*
Y807126D03*
X26378Y822874D03*
Y815000D03*
X34252Y830748D03*
X26378D03*
X34252Y1146890D03*
Y1139016D03*
X26378Y1146890D03*
Y1139016D03*
X34252Y1170512D03*
Y1154764D03*
X26378Y1162638D03*
Y1154764D03*
X34252Y1194134D03*
Y1186260D03*
Y1178386D03*
X26378Y1194134D03*
Y1186260D03*
Y1178386D03*
X169291Y48858D03*
Y56732D03*
Y64606D03*
Y72480D03*
Y88228D03*
Y96102D03*
Y103976D03*
Y412244D03*
Y420118D03*
Y427992D03*
Y435866D03*
Y451614D03*
Y459488D03*
Y467362D03*
Y775630D03*
Y783504D03*
Y791378D03*
Y799252D03*
Y815000D03*
Y822874D03*
Y830748D03*
Y1139016D03*
Y1146890D03*
Y1154764D03*
Y1162638D03*
Y1178386D03*
Y1186260D03*
Y1194134D03*
X177165Y48858D03*
Y56732D03*
Y64606D03*
Y80354D03*
Y88228D03*
Y96102D03*
Y103976D03*
Y412244D03*
Y420118D03*
Y427992D03*
Y443740D03*
Y451614D03*
Y459488D03*
Y467362D03*
Y775630D03*
Y783504D03*
Y791378D03*
Y807126D03*
Y815000D03*
Y822874D03*
Y830748D03*
Y1139016D03*
Y1146890D03*
Y1154764D03*
Y1170512D03*
Y1178386D03*
Y1186260D03*
Y1194134D03*
G54D12*
X-63431Y837184D03*
Y1152816D03*
X-53431Y837184D03*
Y1152816D03*
X-32318Y837184D03*
X-22318D03*
X-32318Y1152816D03*
X-22318D03*
G54D20*
X30315Y41378D03*
Y404764D03*
Y768150D03*
Y1131536D03*
X173228Y111456D03*
Y474842D03*
Y838228D03*
Y1201614D03*
G54D30*
X101772Y1287047D03*
G54D31*
X169291Y80354D03*
Y443740D03*
Y807126D03*
Y1170512D03*
X177165Y72480D03*
Y435866D03*
Y799252D03*
Y1162638D03*
G54D14*
X-27318Y824000D03*
G54D11*
X-58431D03*
G54D10*
X-58189Y19685D03*
Y619685D03*
Y1307087D03*
X865353Y19685D03*
Y1307087D03*
G54D28*
X20000Y1307000D03*
X44000Y17500D03*
X178500D03*
G54D16*
X3005Y30675D03*
Y50675D03*
Y70675D03*
Y90675D03*
Y110675D03*
Y130675D03*
Y150675D03*
Y170675D03*
X8908Y163243D03*
Y160243D03*
X3005Y190675D03*
Y210675D03*
Y230675D03*
Y250675D03*
Y270675D03*
Y290675D03*
Y310675D03*
Y330675D03*
Y350675D03*
Y370675D03*
Y390675D03*
Y410675D03*
Y430675D03*
Y450675D03*
Y470675D03*
Y490675D03*
Y510675D03*
Y530675D03*
Y550675D03*
Y570675D03*
Y590675D03*
Y610675D03*
Y630675D03*
Y650675D03*
Y670675D03*
Y690675D03*
Y710675D03*
Y730675D03*
Y750675D03*
Y770675D03*
Y790675D03*
Y810675D03*
Y830675D03*
Y850675D03*
Y870675D03*
Y890675D03*
Y910675D03*
Y930675D03*
Y950675D03*
Y970675D03*
Y990675D03*
Y1010675D03*
Y1030675D03*
Y1050675D03*
Y1070675D03*
Y1090675D03*
Y1110675D03*
Y1130675D03*
Y1150675D03*
Y1170675D03*
Y1190675D03*
Y1210675D03*
Y1230675D03*
Y1250675D03*
Y1270675D03*
Y1290675D03*
Y1310675D03*
X15868Y3010D03*
X11874Y154893D03*
X13708Y173943D03*
Y170943D03*
X11208Y173943D03*
Y170943D03*
X29500Y520500D03*
Y512500D03*
X12800Y870600D03*
X15600D03*
X12864Y873315D03*
Y876315D03*
Y879315D03*
X15664D03*
Y876315D03*
Y873315D03*
X16017Y1323770D03*
X34927Y3006D03*
X54927D03*
X37500Y520500D03*
Y512500D03*
X51164Y988115D03*
Y985115D03*
X48664D03*
Y988115D03*
X51164Y994115D03*
Y991115D03*
X48664D03*
Y994115D03*
X35517Y1323770D03*
X56017D03*
X61802Y25927D03*
X68508Y50969D03*
X78500Y512500D03*
Y504500D03*
X73500Y562200D03*
X74857Y611575D03*
X76017Y1323770D03*
X91059Y94630D03*
Y452760D03*
X85500Y472975D03*
X86500Y512500D03*
Y504500D03*
X92950Y821707D03*
X82000Y833575D03*
X94730Y1173910D03*
X96017Y1323770D03*
X120000Y512500D03*
Y504500D03*
X114000Y591000D03*
X116017Y1323770D03*
X146740Y3016D03*
X141748Y26922D03*
X135014Y50977D03*
X128000Y512500D03*
Y504500D03*
X136017Y1323770D03*
X165799Y3002D03*
X169000Y522000D03*
Y514000D03*
X156017Y1323770D03*
X185799Y3002D03*
X193719Y157489D03*
X191219D03*
X192164Y164843D03*
X189664D03*
X192164Y167843D03*
X189664D03*
X192164Y170843D03*
X189664D03*
X192164Y173843D03*
X189664D03*
X186964Y189043D03*
Y186043D03*
Y199543D03*
Y196543D03*
X186764Y208743D03*
Y205743D03*
X177000Y522000D03*
Y514000D03*
X193964Y887015D03*
Y890015D03*
Y893015D03*
Y896015D03*
X180264Y895915D03*
Y892915D03*
Y889915D03*
X193964Y899015D03*
X180264Y898915D03*
X176017Y1323770D03*
X194471Y1321882D03*
X199120Y9903D03*
X200536Y29059D03*
Y49059D03*
Y69059D03*
Y109059D03*
Y89059D03*
Y129059D03*
Y149059D03*
Y169059D03*
Y189059D03*
Y209059D03*
Y249059D03*
Y229059D03*
Y269059D03*
Y289059D03*
Y309059D03*
Y329059D03*
Y349059D03*
Y369059D03*
Y409059D03*
Y389059D03*
Y429059D03*
Y449059D03*
Y469059D03*
Y489059D03*
Y509059D03*
Y549059D03*
Y529059D03*
Y569059D03*
Y589059D03*
Y609059D03*
Y629059D03*
Y649059D03*
Y669059D03*
Y709059D03*
Y689059D03*
Y729059D03*
Y749059D03*
Y769059D03*
Y789059D03*
Y809059D03*
Y849059D03*
Y829059D03*
Y869059D03*
Y889059D03*
Y909059D03*
Y929059D03*
Y947059D03*
Y969059D03*
Y1009059D03*
Y989059D03*
Y1029059D03*
Y1049059D03*
Y1069059D03*
Y1089059D03*
Y1109059D03*
Y1149059D03*
Y1129059D03*
Y1169059D03*
Y1189059D03*
Y1209059D03*
Y1229059D03*
Y1249059D03*
Y1289059D03*
Y1269059D03*
Y1309059D03*
G54D18*
X6025Y734000D03*
X6000Y727000D03*
X6025Y748000D03*
Y741000D03*
X27185Y286228D03*
X21185D03*
X24185D03*
X27185Y289228D03*
X21185D03*
X24185D03*
X18185Y286228D03*
Y289228D03*
X14000Y335928D03*
X17000D03*
X20000D03*
X23000D03*
X26000D03*
X11000Y520000D03*
Y515500D03*
Y506500D03*
X26500Y732500D03*
X13425Y712500D03*
X16985Y1028800D03*
X19985D03*
Y1015800D03*
X16985D03*
X19985Y1012800D03*
X16985D03*
X22985Y1028800D03*
X25985D03*
Y1015800D03*
X22985D03*
X25985Y1012800D03*
X22985D03*
X26000Y1062720D03*
X23000D03*
X20000D03*
X17000D03*
X14000D03*
X10241Y1234150D03*
X11000Y1239500D03*
X23500Y1237000D03*
X47561Y280228D03*
X40185Y301728D03*
X37185D03*
X54926Y296651D03*
X49250Y516750D03*
X35484Y534075D03*
X33500Y694425D03*
X48005Y1012038D03*
X37555Y1027168D03*
X40555D03*
X53000Y1021500D03*
X56000Y1203273D03*
X78400Y40200D03*
Y36700D03*
Y33200D03*
Y47200D03*
Y43700D03*
X75173Y78000D03*
X61500Y97500D03*
X58700Y110900D03*
X56730Y278169D03*
X77773Y420228D03*
X60773Y443728D03*
Y457228D03*
X74500Y475000D03*
X74626Y515080D03*
X68500Y537075D03*
X66400Y655400D03*
X65552Y645503D03*
X74075Y732000D03*
X76500Y746500D03*
X61000Y810000D03*
X60773Y820614D03*
X71650Y821000D03*
X64108Y1006500D03*
X56245Y1004000D03*
X77773Y1147500D03*
X61000Y1172500D03*
X57500Y1181000D03*
X85500Y40000D03*
Y36500D03*
Y33000D03*
Y47000D03*
Y43500D03*
X86500Y481500D03*
X98925Y524000D03*
Y512500D03*
X83300Y624100D03*
X86000Y680000D03*
Y688000D03*
Y696000D03*
X93000Y731000D03*
X93025Y738000D03*
X93000Y745000D03*
X99000Y853000D03*
X122917Y39800D03*
Y37300D03*
Y49800D03*
Y47300D03*
Y44800D03*
Y42300D03*
X114500Y127000D03*
X127482Y286228D03*
X124378Y409308D03*
X125200Y453800D03*
X113500Y476000D03*
X105815Y488500D03*
X105732Y496844D03*
X116000Y529500D03*
X126500Y706500D03*
X115563Y759063D03*
X125500Y820114D03*
X125227Y815000D03*
X126000Y834500D03*
X126500Y1129000D03*
X125000Y1198000D03*
X125917Y39800D03*
Y37300D03*
Y49800D03*
Y47300D03*
Y44800D03*
Y42300D03*
X135500Y70441D03*
X142727Y79842D03*
Y94000D03*
X134525Y107842D03*
X141327Y115542D03*
X125500Y118000D03*
X127482Y289228D03*
X133482D03*
X130482D03*
X136482D03*
X133482Y286228D03*
X130482D03*
X136482D03*
X146482Y301728D03*
X128000Y348300D03*
X127900Y345100D03*
Y364300D03*
Y351800D03*
X127800Y370900D03*
X127900Y367900D03*
X141327Y398000D03*
X136000Y429941D03*
X129314Y414545D03*
X145327Y416500D03*
X142727Y428000D03*
X125500Y469600D03*
X135349Y468652D03*
X134000Y501000D03*
X134575Y659000D03*
X146000Y729000D03*
X127983Y736234D03*
X144827Y763510D03*
X129705Y777796D03*
X132350Y793241D03*
X142727Y791500D03*
X141993Y800295D03*
X141327Y822814D03*
X134525Y815114D03*
X131882Y1012900D03*
X134882D03*
X131882Y1015900D03*
X134882D03*
X125882Y1012900D03*
X128882D03*
X125882Y1015900D03*
X128882D03*
X146482Y1028500D03*
X141649Y1141500D03*
X135500Y1143441D03*
X142088Y1131281D03*
X132350Y1156741D03*
X142727Y1151000D03*
X142500Y1183500D03*
X125440Y1175970D03*
X135000Y1197500D03*
X156858Y280228D03*
X166499Y276483D03*
X149482Y301728D03*
X164296Y297723D03*
X170000Y504500D03*
X169000Y542075D03*
X167075Y756500D03*
X151300Y756400D03*
X149500Y850500D03*
X156858Y1007000D03*
X166358Y1004941D03*
X149482Y1028500D03*
X162500Y1023000D03*
X172905Y279728D03*
X177458Y335828D03*
X180458D03*
X186458D03*
X183458D03*
X191575Y518500D03*
X179000Y535075D03*
X181475Y713000D03*
X193475Y706000D03*
X181475Y720000D03*
X192582Y733000D03*
X181475Y740000D03*
Y747000D03*
X182285Y982200D03*
X179285D03*
X188285D03*
X185285D03*
X172905Y1006500D03*
X190358Y1062764D03*
X187358D03*
X184358D03*
X181358D03*
Y1060064D03*
X184358D03*
X187358D03*
X190358D03*
X192500Y1215000D03*
X182741Y1235150D03*
X183500Y1240500D03*
X195000Y490500D03*
X195500Y495000D03*
Y497500D03*
Y1220000D03*
Y1222500D03*
G54D19*
X8000Y1220000D03*
Y1222500D03*
X11000Y1215000D03*
G54D22*
X34252Y72480D03*
X26378Y80354D03*
X34252Y435866D03*
X26378Y443740D03*
X34252Y799252D03*
X26378Y807126D03*
X34252Y1162638D03*
X26378Y1170512D03*
G54D13*
X-58431Y1166000D03*
G54D15*
X-27318D03*
%LPC*%
G75*
G54D32*
G01X-320500Y-470483D02*
Y2626000D01*
X2967000D01*
Y-470483D01*
X-320500D01*
G01X329322Y-314459D02*
Y-319459D01*
G01X327865Y-314459D02*
X330779D01*
G01X335689Y-319459D02*
X333155D01*
Y-314459D01*
X335689D01*
G01X334675Y-316876D02*
X333155D01*
G01X338255Y-314459D02*
Y-319459D01*
X340789D01*
G01X344622Y-319626D02*
X344495Y-319542D01*
Y-319376D01*
X344622Y-319292D01*
X344749Y-319376D01*
Y-319542D01*
X344622Y-319626D01*
G01Y-317376D02*
X344495Y-317292D01*
Y-317126D01*
X344622Y-317042D01*
X344749Y-317126D01*
Y-317292D01*
X344622Y-317376D01*
G01X349405Y-321126D02*
X348772Y-320292D01*
X348455Y-319459D01*
Y-316126D01*
X348772Y-315292D01*
X349405Y-314459D01*
G01X354822D02*
X354315Y-314626D01*
X353935Y-315042D01*
X353682Y-315542D01*
X353492Y-316209D01*
X353429Y-316959D01*
X353492Y-317709D01*
X353682Y-318376D01*
X353935Y-318876D01*
X354315Y-319292D01*
X354822Y-319459D01*
X355329Y-319292D01*
X355709Y-318876D01*
X355962Y-318376D01*
X356152Y-317709D01*
X356215Y-316959D01*
X356152Y-316209D01*
X355962Y-315542D01*
X355709Y-315042D01*
X355329Y-314626D01*
X354822Y-314459D01*
G01X358529Y-318459D02*
X358909Y-319042D01*
X359415Y-319376D01*
X359985Y-319459D01*
X360492Y-319376D01*
X360999Y-318959D01*
X361315Y-318459D01*
X361379Y-317959D01*
X361252Y-317376D01*
X360809Y-316959D01*
X360365Y-316792D01*
X359795D01*
G01X360365D02*
X360745Y-316542D01*
X361062Y-316126D01*
X361189Y-315626D01*
X361062Y-315126D01*
X360745Y-314709D01*
X360175Y-314459D01*
X359605Y-314542D01*
X359035Y-314876D01*
G01X365339Y-321126D02*
X365972Y-320292D01*
X366289Y-319459D01*
Y-316126D01*
X365972Y-315292D01*
X365339Y-314459D01*
G01X368729Y-318459D02*
X369109Y-319042D01*
X369615Y-319376D01*
X370185Y-319459D01*
X370692Y-319376D01*
X371199Y-318959D01*
X371515Y-318459D01*
X371579Y-317959D01*
X371452Y-317376D01*
X371009Y-316959D01*
X370565Y-316792D01*
X369995D01*
G01X370565D02*
X370945Y-316542D01*
X371262Y-316126D01*
X371389Y-315626D01*
X371262Y-315126D01*
X370945Y-314709D01*
X370375Y-314459D01*
X369805Y-314542D01*
X369235Y-314876D01*
G01X374019Y-315292D02*
X374399Y-314792D01*
X374842Y-314542D01*
X375349Y-314459D01*
X375982Y-314626D01*
X376425Y-315042D01*
X376552Y-315542D01*
X376489Y-316042D01*
X376235Y-316459D01*
X374969Y-317292D01*
X374399Y-317876D01*
X374019Y-318709D01*
X373892Y-319459D01*
X376552D01*
G01X380195D02*
X380322Y-318376D01*
X380512Y-317459D01*
X380765Y-316626D01*
X381082Y-315709D01*
X381589Y-314459D01*
X379055D01*
G01X384599Y-317792D02*
X386245D01*
G01X389319Y-315292D02*
X389699Y-314792D01*
X390142Y-314542D01*
X390649Y-314459D01*
X391282Y-314626D01*
X391725Y-315042D01*
X391852Y-315542D01*
X391789Y-316042D01*
X391535Y-316459D01*
X390269Y-317292D01*
X389699Y-317876D01*
X389319Y-318709D01*
X389192Y-319459D01*
X391852D01*
G01X394229Y-318459D02*
X394609Y-319042D01*
X395115Y-319376D01*
X395685Y-319459D01*
X396192Y-319376D01*
X396699Y-318959D01*
X397015Y-318459D01*
X397079Y-317959D01*
X396952Y-317376D01*
X396509Y-316959D01*
X396065Y-316792D01*
X395495D01*
G01X396065D02*
X396445Y-316542D01*
X396762Y-316126D01*
X396889Y-315626D01*
X396762Y-315126D01*
X396445Y-314709D01*
X395875Y-314459D01*
X395305Y-314542D01*
X394735Y-314876D01*
G01X401482Y-319459D02*
Y-314459D01*
X399139Y-318042D01*
X402305D01*
G01X404429Y-318709D02*
X404809Y-319126D01*
X405252Y-319376D01*
X405822Y-319459D01*
X406392Y-319292D01*
X406835Y-318959D01*
X407152Y-318376D01*
X407215Y-317709D01*
X407089Y-317042D01*
X406772Y-316626D01*
X406329Y-316292D01*
X405885Y-316209D01*
X405442Y-316292D01*
X404872Y-316626D01*
X405062Y-314459D01*
X406772D01*
G01X414819Y-319459D02*
Y-314459D01*
X417225D01*
G01X416339Y-316876D02*
X414819D01*
G01X419539Y-319459D02*
X421122Y-314459D01*
X422705Y-319459D01*
G01X422135Y-317709D02*
X420109D01*
G01X424892Y-319459D02*
X427552Y-314459D01*
G01X424892D02*
X427552Y-319459D01*
G01X431322Y-319626D02*
X431195Y-319542D01*
Y-319376D01*
X431322Y-319292D01*
X431449Y-319376D01*
Y-319542D01*
X431322Y-319626D01*
G01Y-317376D02*
X431195Y-317292D01*
Y-317126D01*
X431322Y-317042D01*
X431449Y-317126D01*
Y-317292D01*
X431322Y-317376D01*
G01X436105Y-321126D02*
X435472Y-320292D01*
X435155Y-319459D01*
Y-316126D01*
X435472Y-315292D01*
X436105Y-314459D01*
G01X441522D02*
X441015Y-314626D01*
X440635Y-315042D01*
X440382Y-315542D01*
X440192Y-316209D01*
X440129Y-316959D01*
X440192Y-317709D01*
X440382Y-318376D01*
X440635Y-318876D01*
X441015Y-319292D01*
X441522Y-319459D01*
X442029Y-319292D01*
X442409Y-318876D01*
X442662Y-318376D01*
X442852Y-317709D01*
X442915Y-316959D01*
X442852Y-316209D01*
X442662Y-315542D01*
X442409Y-315042D01*
X442029Y-314626D01*
X441522Y-314459D01*
G01X445229Y-318459D02*
X445609Y-319042D01*
X446115Y-319376D01*
X446685Y-319459D01*
X447192Y-319376D01*
X447699Y-318959D01*
X448015Y-318459D01*
X448079Y-317959D01*
X447952Y-317376D01*
X447509Y-316959D01*
X447065Y-316792D01*
X446495D01*
G01X447065D02*
X447445Y-316542D01*
X447762Y-316126D01*
X447889Y-315626D01*
X447762Y-315126D01*
X447445Y-314709D01*
X446875Y-314459D01*
X446305Y-314542D01*
X445735Y-314876D01*
G01X452039Y-321126D02*
X452672Y-320292D01*
X452989Y-319459D01*
Y-316126D01*
X452672Y-315292D01*
X452039Y-314459D01*
G01X455429Y-318459D02*
X455809Y-319042D01*
X456315Y-319376D01*
X456885Y-319459D01*
X457392Y-319376D01*
X457899Y-318959D01*
X458215Y-318459D01*
X458279Y-317959D01*
X458152Y-317376D01*
X457709Y-316959D01*
X457265Y-316792D01*
X456695D01*
G01X457265D02*
X457645Y-316542D01*
X457962Y-316126D01*
X458089Y-315626D01*
X457962Y-315126D01*
X457645Y-314709D01*
X457075Y-314459D01*
X456505Y-314542D01*
X455935Y-314876D01*
G01X460845Y-318876D02*
X461289Y-319292D01*
X461795Y-319459D01*
X462302Y-319292D01*
X462745Y-318792D01*
X463062Y-318042D01*
X463189Y-317292D01*
Y-316376D01*
X463062Y-315626D01*
X462745Y-314959D01*
X462365Y-314626D01*
X461922Y-314459D01*
X461415Y-314626D01*
X461035Y-314959D01*
X460782Y-315459D01*
X460655Y-316126D01*
X460782Y-316709D01*
X461099Y-317292D01*
X461479Y-317626D01*
X461922Y-317709D01*
X462429Y-317542D01*
X462809Y-317126D01*
X463189Y-316376D01*
G01X466895Y-319459D02*
X467022Y-318376D01*
X467212Y-317459D01*
X467465Y-316626D01*
X467782Y-315709D01*
X468289Y-314459D01*
X465755D01*
G01X471299Y-317792D02*
X472945D01*
G01X475829Y-318459D02*
X476209Y-319042D01*
X476715Y-319376D01*
X477285Y-319459D01*
X477792Y-319376D01*
X478299Y-318959D01*
X478615Y-318459D01*
X478679Y-317959D01*
X478552Y-317376D01*
X478109Y-316959D01*
X477665Y-316792D01*
X477095D01*
G01X477665D02*
X478045Y-316542D01*
X478362Y-316126D01*
X478489Y-315626D01*
X478362Y-315126D01*
X478045Y-314709D01*
X477475Y-314459D01*
X476905Y-314542D01*
X476335Y-314876D01*
G01X481119Y-317376D02*
X481562Y-316792D01*
X481942Y-316459D01*
X482449Y-316292D01*
X482892Y-316459D01*
X483209Y-316792D01*
X483462Y-317292D01*
X483525Y-317876D01*
X483462Y-318376D01*
X483209Y-318876D01*
X482829Y-319292D01*
X482385Y-319459D01*
X481879Y-319292D01*
X481435Y-318792D01*
X481182Y-318042D01*
X481119Y-317209D01*
X481245Y-316126D01*
X481435Y-315542D01*
X481752Y-314959D01*
X482195Y-314542D01*
X482639Y-314459D01*
X483082Y-314626D01*
X483399Y-315042D01*
G01X487422Y-319459D02*
Y-314459D01*
X486662Y-315459D01*
G01Y-319459D02*
X488182D01*
G01X493282D02*
Y-314459D01*
X490939Y-318042D01*
X494105D01*
G01X317322Y-249459D02*
Y-324459D01*
X817322D01*
Y-249459D01*
X317322D01*
G01X512322D02*
Y-324459D01*
G01Y-299459D02*
X615322D01*
Y-274459D01*
G01X512322D02*
X615322D01*
G01X622829Y-309459D02*
Y-304459D01*
X624095D01*
X624602Y-304709D01*
X624982Y-305042D01*
X625299Y-305542D01*
X625552Y-306126D01*
X625615Y-306959D01*
X625552Y-307792D01*
X625299Y-308376D01*
X624982Y-308876D01*
X624602Y-309209D01*
X624095Y-309459D01*
X622829D01*
G01X627739D02*
X629322Y-304459D01*
X630905Y-309459D01*
G01X630335Y-307709D02*
X628309D01*
G01X634422Y-304459D02*
Y-309459D01*
G01X632965Y-304459D02*
X635879D01*
G01X640789Y-309459D02*
X638255D01*
Y-304459D01*
X640789D01*
G01X639775Y-306876D02*
X638255D01*
G01X644622Y-309626D02*
X644495Y-309542D01*
Y-309376D01*
X644622Y-309292D01*
X644749Y-309376D01*
Y-309542D01*
X644622Y-309626D01*
G01Y-307376D02*
X644495Y-307292D01*
Y-307126D01*
X644622Y-307042D01*
X644749Y-307126D01*
Y-307292D01*
X644622Y-307376D01*
G01X617322Y-249459D02*
Y-324459D01*
G01X615322Y-249459D02*
Y-324459D01*
G01X622955Y-284459D02*
Y-279459D01*
X624475D01*
X624982Y-279709D01*
X625362Y-280292D01*
X625489Y-280959D01*
X625362Y-281626D01*
X625045Y-282126D01*
X624475Y-282376D01*
X622955D01*
G01X628182Y-284626D02*
X630462Y-279459D01*
G01X632965Y-284459D02*
Y-279459D01*
X635879Y-284459D01*
Y-279459D01*
G01X639522Y-284626D02*
X639395Y-284542D01*
Y-284376D01*
X639522Y-284292D01*
X639649Y-284376D01*
Y-284542D01*
X639522Y-284626D01*
G01Y-282376D02*
X639395Y-282292D01*
Y-282126D01*
X639522Y-282042D01*
X639649Y-282126D01*
Y-282292D01*
X639522Y-282376D01*
G01X617322Y-299459D02*
X817322D01*
G01X622955Y-259459D02*
Y-254459D01*
X624475D01*
X624982Y-254709D01*
X625362Y-255292D01*
X625489Y-255959D01*
X625362Y-256626D01*
X625045Y-257126D01*
X624475Y-257376D01*
X622955D01*
G01X628055Y-259459D02*
Y-254459D01*
X629639D01*
X630145Y-254709D01*
X630462Y-255042D01*
X630589Y-255709D01*
X630462Y-256376D01*
X630082Y-256792D01*
X629639Y-257042D01*
X628055D01*
G01X629639D02*
X630589Y-259459D01*
G01X634422D02*
X633915Y-259376D01*
X633472Y-259042D01*
X633092Y-258542D01*
X632839Y-257959D01*
X632712Y-257292D01*
Y-256626D01*
X632839Y-255959D01*
X633092Y-255376D01*
X633472Y-254876D01*
X633915Y-254542D01*
X634422Y-254459D01*
X634929Y-254542D01*
X635372Y-254876D01*
X635752Y-255376D01*
X636005Y-255959D01*
X636132Y-256626D01*
Y-257292D01*
X636005Y-257959D01*
X635752Y-258542D01*
X635372Y-259042D01*
X634929Y-259376D01*
X634422Y-259459D01*
G01X638255Y-258459D02*
X638572Y-258959D01*
X638952Y-259292D01*
X639395Y-259459D01*
X639902Y-259292D01*
X640282Y-258959D01*
X640662Y-258459D01*
X640789Y-257792D01*
Y-254459D01*
G01X645889Y-259459D02*
X643355D01*
Y-254459D01*
X645889D01*
G01X644875Y-256876D02*
X643355D01*
G01X651115Y-254876D02*
X650735Y-254626D01*
X650292Y-254459D01*
X649785D01*
X649215Y-254709D01*
X648772Y-255126D01*
X648455Y-255626D01*
X648202Y-256459D01*
X648139Y-257209D01*
X648265Y-257959D01*
X648455Y-258459D01*
X648835Y-258959D01*
X649279Y-259292D01*
X649722Y-259459D01*
X650165D01*
X650609Y-259292D01*
X650989Y-259042D01*
X651305Y-258709D01*
G01X654822Y-254459D02*
Y-259459D01*
G01X653365Y-254459D02*
X656279D01*
G01X659922Y-259626D02*
X659795Y-259542D01*
Y-259376D01*
X659922Y-259292D01*
X660049Y-259376D01*
Y-259542D01*
X659922Y-259626D01*
G01Y-257376D02*
X659795Y-257292D01*
Y-257126D01*
X659922Y-257042D01*
X660049Y-257126D01*
Y-257292D01*
X659922Y-257376D01*
G01X617322Y-274459D02*
X817322D01*
G01X734955Y-301959D02*
Y-306959D01*
X737489D01*
G01X740562Y-301959D02*
X742082D01*
G01X741322D02*
Y-306959D01*
G01X740562D02*
X742082D01*
G01X746929Y-304292D02*
X747182Y-304042D01*
X747372Y-303626D01*
X747499Y-303042D01*
X747372Y-302542D01*
X747119Y-302209D01*
X746675Y-301959D01*
X744965D01*
Y-306959D01*
X747055D01*
X747499Y-306626D01*
X747752Y-306126D01*
X747879Y-305542D01*
X747752Y-304959D01*
X747372Y-304459D01*
X746929Y-304292D01*
X744965D01*
G01X751522Y-307126D02*
X751395Y-307042D01*
Y-306876D01*
X751522Y-306792D01*
X751649Y-306876D01*
Y-307042D01*
X751522Y-307126D01*
G01Y-304876D02*
X751395Y-304792D01*
Y-304626D01*
X751522Y-304542D01*
X751649Y-304626D01*
Y-304792D01*
X751522Y-304876D01*
G01X732322Y-299459D02*
Y-324459D01*
G01X779222Y-301959D02*
Y-306959D01*
G01X777765Y-301959D02*
X780679D01*
G01X784322Y-306959D02*
X783942Y-306876D01*
X783562Y-306542D01*
X783309Y-305959D01*
X783182Y-305292D01*
X783309Y-304626D01*
X783562Y-304042D01*
X783942Y-303709D01*
X784322Y-303626D01*
X784702Y-303709D01*
X785082Y-304042D01*
X785335Y-304626D01*
X785399Y-305292D01*
X785335Y-305959D01*
X785082Y-306542D01*
X784702Y-306876D01*
X784322Y-306959D01*
G01X789422D02*
X789042Y-306876D01*
X788662Y-306542D01*
X788409Y-305959D01*
X788282Y-305292D01*
X788409Y-304626D01*
X788662Y-304042D01*
X789042Y-303709D01*
X789422Y-303626D01*
X789802Y-303709D01*
X790182Y-304042D01*
X790435Y-304626D01*
X790499Y-305292D01*
X790435Y-305959D01*
X790182Y-306542D01*
X789802Y-306876D01*
X789422Y-306959D01*
G01X794522D02*
Y-301959D01*
G01X799622Y-307126D02*
X799495Y-307042D01*
Y-306876D01*
X799622Y-306792D01*
X799749Y-306876D01*
Y-307042D01*
X799622Y-307126D01*
G01Y-304876D02*
X799495Y-304792D01*
Y-304626D01*
X799622Y-304542D01*
X799749Y-304626D01*
Y-304792D01*
X799622Y-304876D01*
G01X775322Y-299459D02*
Y-324459D01*
G01Y-274459D02*
Y-299459D01*
G01X777955Y-281959D02*
Y-276959D01*
X779539D01*
X780045Y-277209D01*
X780362Y-277542D01*
X780489Y-278209D01*
X780362Y-278876D01*
X779982Y-279292D01*
X779539Y-279542D01*
X777955D01*
G01X779539D02*
X780489Y-281959D01*
G01X785589D02*
X783055D01*
Y-276959D01*
X785589D01*
G01X784575Y-279376D02*
X783055D01*
G01X787839Y-276959D02*
X789422Y-281959D01*
X791005Y-276959D01*
G01X794522Y-282126D02*
X794395Y-282042D01*
Y-281876D01*
X794522Y-281792D01*
X794649Y-281876D01*
Y-282042D01*
X794522Y-282126D01*
G01Y-279876D02*
X794395Y-279792D01*
Y-279626D01*
X794522Y-279542D01*
X794649Y-279626D01*
Y-279792D01*
X794522Y-279876D01*
G01X798082Y-326159D02*
X798162Y-326084D01*
X798222Y-325959D01*
X798262Y-325784D01*
X798222Y-325634D01*
X798142Y-325534D01*
X798002Y-325459D01*
X797462D01*
Y-326959D01*
X798122D01*
X798262Y-326859D01*
X798342Y-326709D01*
X798382Y-326534D01*
X798342Y-326359D01*
X798222Y-326209D01*
X798082Y-326159D01*
X797462D01*
G01X799482Y-326959D02*
Y-325959D01*
G01Y-326134D02*
X799402Y-326034D01*
X799282Y-325984D01*
X799142Y-325959D01*
X799002Y-326009D01*
X798882Y-326109D01*
X798802Y-326259D01*
X798762Y-326459D01*
X798802Y-326659D01*
X798882Y-326809D01*
X799002Y-326909D01*
X799142Y-326959D01*
X799282Y-326934D01*
X799402Y-326859D01*
X799482Y-326759D01*
G01X800022Y-326784D02*
X800122Y-326884D01*
X800262Y-326959D01*
X800382D01*
X800502Y-326909D01*
X800582Y-326834D01*
X800622Y-326734D01*
X800602Y-326584D01*
X800522Y-326509D01*
X800162Y-326359D01*
X800082Y-326184D01*
X800122Y-326059D01*
X800202Y-325984D01*
X800322Y-325959D01*
X800442Y-325984D01*
X800562Y-326059D01*
G01X801222Y-326284D02*
X801862D01*
X801802Y-326109D01*
X801702Y-326009D01*
X801562Y-325959D01*
X801422Y-325984D01*
X801302Y-326059D01*
X801222Y-326234D01*
X801182Y-326384D01*
Y-326534D01*
X801222Y-326684D01*
X801322Y-326834D01*
X801442Y-326934D01*
X801582Y-326959D01*
X801722Y-326909D01*
X801862Y-326759D01*
G01X802362Y-326959D02*
Y-325459D01*
G01Y-326209D02*
X802462Y-326059D01*
X802582Y-325984D01*
X802702Y-325959D01*
X802882Y-326009D01*
X803002Y-326109D01*
X803082Y-326284D01*
Y-326484D01*
X803042Y-326684D01*
X802962Y-326834D01*
X802822Y-326934D01*
X802702Y-326959D01*
X802582Y-326934D01*
X802462Y-326859D01*
X802362Y-326734D01*
G01X803922Y-326959D02*
X803802Y-326934D01*
X803682Y-326834D01*
X803602Y-326659D01*
X803562Y-326459D01*
X803602Y-326259D01*
X803682Y-326084D01*
X803802Y-325984D01*
X803922Y-325959D01*
X804042Y-325984D01*
X804162Y-326084D01*
X804242Y-326259D01*
X804262Y-326459D01*
X804242Y-326659D01*
X804162Y-326834D01*
X804042Y-326934D01*
X803922Y-326959D01*
G01X805482D02*
Y-325959D01*
G01Y-326134D02*
X805402Y-326034D01*
X805282Y-325984D01*
X805142Y-325959D01*
X805002Y-326009D01*
X804882Y-326109D01*
X804802Y-326259D01*
X804762Y-326459D01*
X804802Y-326659D01*
X804882Y-326809D01*
X805002Y-326909D01*
X805142Y-326959D01*
X805282Y-326934D01*
X805402Y-326859D01*
X805482Y-326759D01*
G01X806042Y-326959D02*
Y-325959D01*
G01Y-326159D02*
X806142Y-326059D01*
X806242Y-325984D01*
X806382Y-325959D01*
X806482Y-325984D01*
X806602Y-326059D01*
G01X807882Y-325459D02*
Y-326959D01*
G01Y-326734D02*
X807802Y-326859D01*
X807682Y-326934D01*
X807542Y-326959D01*
X807382Y-326909D01*
X807262Y-326784D01*
X807182Y-326634D01*
X807162Y-326459D01*
X807182Y-326284D01*
X807262Y-326134D01*
X807382Y-326009D01*
X807542Y-325959D01*
X807682Y-325984D01*
X807782Y-326034D01*
X807882Y-326134D01*
G01X809522Y-326959D02*
Y-325459D01*
X810022D01*
X810182Y-325534D01*
X810282Y-325634D01*
X810322Y-325834D01*
X810282Y-326034D01*
X810162Y-326159D01*
X810022Y-326234D01*
X809522D01*
G01X810022D02*
X810322Y-326959D01*
G01X810822Y-326284D02*
X811462D01*
X811402Y-326109D01*
X811302Y-326009D01*
X811162Y-325959D01*
X811022Y-325984D01*
X810902Y-326059D01*
X810822Y-326234D01*
X810782Y-326384D01*
Y-326534D01*
X810822Y-326684D01*
X810922Y-326834D01*
X811042Y-326934D01*
X811182Y-326959D01*
X811322Y-326909D01*
X811462Y-326759D01*
G01X811962Y-325959D02*
X812322Y-326959D01*
X812682Y-325959D01*
G01X813522Y-327009D02*
X813482Y-326984D01*
Y-326934D01*
X813522Y-326909D01*
X813562Y-326934D01*
Y-326984D01*
X813522Y-327009D01*
G01X814682Y-326959D02*
X814722Y-326634D01*
X814782Y-326359D01*
X814862Y-326109D01*
X814962Y-325834D01*
X815122Y-325459D01*
X814322D01*
G01X816082Y-326159D02*
X816162Y-326084D01*
X816222Y-325959D01*
X816262Y-325784D01*
X816222Y-325634D01*
X816142Y-325534D01*
X816002Y-325459D01*
X815462D01*
Y-326959D01*
X816122D01*
X816262Y-326859D01*
X816342Y-326709D01*
X816382Y-326534D01*
X816342Y-326359D01*
X816222Y-326209D01*
X816082Y-326159D01*
X815462D01*
G01X-320500Y-470483D02*
Y2626000D01*
X2967000D01*
Y-470483D01*
X-320500D01*
G01X331395Y-304184D02*
X330925Y-303869D01*
X330377Y-303659D01*
X329750D01*
X329045Y-303974D01*
X328497Y-304499D01*
X328105Y-305129D01*
X327792Y-306179D01*
X327714Y-307124D01*
X327870Y-308069D01*
X328105Y-308699D01*
X328575Y-309329D01*
X329124Y-309749D01*
X329672Y-309959D01*
X330220D01*
X330769Y-309749D01*
X331239Y-309434D01*
X331630Y-309014D01*
G01X335032Y-303659D02*
X336912D01*
G01X335972D02*
Y-309959D01*
G01X335032D02*
X336912D01*
G01X342272Y-303659D02*
Y-309959D01*
G01X340470Y-303659D02*
X344074D01*
G01X348572Y-309959D02*
Y-307124D01*
X347005Y-303659D01*
G01X350139D02*
X348572Y-307124D01*
G01X359449Y-308699D02*
X359919Y-309434D01*
X360545Y-309854D01*
X361250Y-309959D01*
X361877Y-309854D01*
X362504Y-309329D01*
X362895Y-308699D01*
X362974Y-308069D01*
X362817Y-307334D01*
X362269Y-306809D01*
X361720Y-306599D01*
X361015D01*
G01X361720D02*
X362190Y-306284D01*
X362582Y-305759D01*
X362739Y-305129D01*
X362582Y-304499D01*
X362190Y-303974D01*
X361485Y-303659D01*
X360780Y-303764D01*
X360075Y-304184D01*
G01X365749Y-308699D02*
X366219Y-309434D01*
X366845Y-309854D01*
X367550Y-309959D01*
X368177Y-309854D01*
X368804Y-309329D01*
X369195Y-308699D01*
X369274Y-308069D01*
X369117Y-307334D01*
X368569Y-306809D01*
X368020Y-306599D01*
X367315D01*
G01X368020D02*
X368490Y-306284D01*
X368882Y-305759D01*
X369039Y-305129D01*
X368882Y-304499D01*
X368490Y-303974D01*
X367785Y-303659D01*
X367080Y-303764D01*
X366375Y-304184D01*
G01X372049Y-308699D02*
X372519Y-309434D01*
X373145Y-309854D01*
X373850Y-309959D01*
X374477Y-309854D01*
X375104Y-309329D01*
X375495Y-308699D01*
X375574Y-308069D01*
X375417Y-307334D01*
X374869Y-306809D01*
X374320Y-306599D01*
X373615D01*
G01X374320D02*
X374790Y-306284D01*
X375182Y-305759D01*
X375339Y-305129D01*
X375182Y-304499D01*
X374790Y-303974D01*
X374085Y-303659D01*
X373380Y-303764D01*
X372675Y-304184D01*
G01X379915Y-309959D02*
X380072Y-308594D01*
X380307Y-307439D01*
X380620Y-306389D01*
X381012Y-305234D01*
X381639Y-303659D01*
X378505D01*
G01X386215Y-309959D02*
X386372Y-308594D01*
X386607Y-307439D01*
X386920Y-306389D01*
X387312Y-305234D01*
X387939Y-303659D01*
X384805D01*
G01X392515Y-311114D02*
X392829Y-309749D01*
G01X398972Y-303659D02*
Y-309959D01*
G01X397170Y-303659D02*
X400774D01*
G01X403314Y-309959D02*
X405272Y-303659D01*
X407230Y-309959D01*
G01X406525Y-307754D02*
X404019D01*
G01X410632Y-303659D02*
X412512D01*
G01X411572D02*
Y-309959D01*
G01X410632D02*
X412512D01*
G01X415522Y-303659D02*
X416619Y-309959D01*
X417872Y-303659D01*
X419125Y-309959D01*
X420222Y-303659D01*
G01X422214Y-309959D02*
X424172Y-303659D01*
X426130Y-309959D01*
G01X425425Y-307754D02*
X422919D01*
G01X428670Y-309959D02*
Y-303659D01*
X432274Y-309959D01*
Y-303659D01*
G01X442680Y-312059D02*
X441897Y-311009D01*
X441505Y-309959D01*
Y-305759D01*
X441897Y-304709D01*
X442680Y-303659D01*
G01X454105Y-309959D02*
Y-303659D01*
X456064D01*
X456690Y-303974D01*
X457082Y-304394D01*
X457239Y-305234D01*
X457082Y-306074D01*
X456612Y-306599D01*
X456064Y-306914D01*
X454105D01*
G01X456064D02*
X457239Y-309959D01*
G01X461972Y-310169D02*
X461815Y-310064D01*
Y-309854D01*
X461972Y-309749D01*
X462129Y-309854D01*
Y-310064D01*
X461972Y-310169D01*
G01X468272Y-309959D02*
X467645Y-309854D01*
X467097Y-309434D01*
X466627Y-308804D01*
X466314Y-308069D01*
X466157Y-307229D01*
Y-306389D01*
X466314Y-305549D01*
X466627Y-304814D01*
X467097Y-304184D01*
X467645Y-303764D01*
X468272Y-303659D01*
X468899Y-303764D01*
X469447Y-304184D01*
X469917Y-304814D01*
X470230Y-305549D01*
X470387Y-306389D01*
Y-307229D01*
X470230Y-308069D01*
X469917Y-308804D01*
X469447Y-309434D01*
X468899Y-309854D01*
X468272Y-309959D01*
G01X474572Y-310169D02*
X474415Y-310064D01*
Y-309854D01*
X474572Y-309749D01*
X474729Y-309854D01*
Y-310064D01*
X474572Y-310169D01*
G01X482595Y-304184D02*
X482125Y-303869D01*
X481577Y-303659D01*
X480950D01*
X480245Y-303974D01*
X479697Y-304499D01*
X479305Y-305129D01*
X478992Y-306179D01*
X478914Y-307124D01*
X479070Y-308069D01*
X479305Y-308699D01*
X479775Y-309329D01*
X480324Y-309749D01*
X480872Y-309959D01*
X481420D01*
X481969Y-309749D01*
X482439Y-309434D01*
X482830Y-309014D01*
G01X487172Y-310169D02*
X487015Y-310064D01*
Y-309854D01*
X487172Y-309749D01*
X487329Y-309854D01*
Y-310064D01*
X487172Y-310169D01*
G01X493864Y-312059D02*
X494647Y-311009D01*
X495039Y-309959D01*
Y-305759D01*
X494647Y-304709D01*
X493864Y-303659D01*
G01X330142Y-296809D02*
X331709D01*
Y-298699D01*
X331239Y-299329D01*
X330690Y-299749D01*
X329907Y-299959D01*
X329124Y-299749D01*
X328575Y-299329D01*
X328105Y-298699D01*
X327792Y-297964D01*
X327635Y-297124D01*
Y-296389D01*
X327792Y-295759D01*
X328105Y-295024D01*
X328575Y-294394D01*
X329045Y-293974D01*
X329672Y-293659D01*
X330220D01*
X330847Y-293869D01*
X331317Y-294289D01*
G01X334249Y-293659D02*
Y-298174D01*
X334562Y-299119D01*
X335189Y-299749D01*
X335972Y-299959D01*
X336755Y-299749D01*
X337382Y-299119D01*
X337695Y-298174D01*
Y-293659D01*
G01X341332D02*
X343212D01*
G01X342272D02*
Y-299959D01*
G01X341332D02*
X343212D01*
G01X346927Y-299119D02*
X347554Y-299644D01*
X348259Y-299959D01*
X348885D01*
X349512Y-299644D01*
X349982Y-299119D01*
X350217Y-298384D01*
X350060Y-297649D01*
X349669Y-297019D01*
X348964Y-296599D01*
X348024Y-296389D01*
X347475Y-295969D01*
X347240Y-295234D01*
X347397Y-294499D01*
X347789Y-293974D01*
X348337Y-293659D01*
X348885D01*
X349434Y-293869D01*
X349904Y-294394D01*
G01X353227Y-299959D02*
Y-293659D01*
G01X356517D02*
Y-299959D01*
G01Y-296809D02*
X353227D01*
G01X359214Y-299959D02*
X361172Y-293659D01*
X363130Y-299959D01*
G01X362425Y-297754D02*
X359919D01*
G01X365670Y-299959D02*
Y-293659D01*
X369274Y-299959D01*
Y-293659D01*
G01X378349Y-299959D02*
Y-293659D01*
X379915D01*
X380542Y-293974D01*
X381012Y-294394D01*
X381404Y-295024D01*
X381717Y-295759D01*
X381795Y-296809D01*
X381717Y-297859D01*
X381404Y-298594D01*
X381012Y-299224D01*
X380542Y-299644D01*
X379915Y-299959D01*
X378349D01*
G01X385432Y-293659D02*
X387312D01*
G01X386372D02*
Y-299959D01*
G01X385432D02*
X387312D01*
G01X391027Y-299119D02*
X391654Y-299644D01*
X392359Y-299959D01*
X392985D01*
X393612Y-299644D01*
X394082Y-299119D01*
X394317Y-298384D01*
X394160Y-297649D01*
X393769Y-297019D01*
X393064Y-296599D01*
X392124Y-296389D01*
X391575Y-295969D01*
X391340Y-295234D01*
X391497Y-294499D01*
X391889Y-293974D01*
X392437Y-293659D01*
X392985D01*
X393534Y-293869D01*
X394004Y-294394D01*
G01X398972Y-293659D02*
Y-299959D01*
G01X397170Y-293659D02*
X400774D01*
G01X405272Y-300169D02*
X405115Y-300064D01*
Y-299854D01*
X405272Y-299749D01*
X405429Y-299854D01*
Y-300064D01*
X405272Y-300169D01*
G01X411415Y-301114D02*
X411729Y-299749D01*
G01X417872Y-293659D02*
Y-299959D01*
G01X416070Y-293659D02*
X419674D01*
G01X422214Y-299959D02*
X424172Y-293659D01*
X426130Y-299959D01*
G01X425425Y-297754D02*
X422919D01*
G01X430472Y-299959D02*
X429845Y-299854D01*
X429297Y-299434D01*
X428827Y-298804D01*
X428514Y-298069D01*
X428357Y-297229D01*
Y-296389D01*
X428514Y-295549D01*
X428827Y-294814D01*
X429297Y-294184D01*
X429845Y-293764D01*
X430472Y-293659D01*
X431099Y-293764D01*
X431647Y-294184D01*
X432117Y-294814D01*
X432430Y-295549D01*
X432587Y-296389D01*
Y-297229D01*
X432430Y-298069D01*
X432117Y-298804D01*
X431647Y-299434D01*
X431099Y-299854D01*
X430472Y-299959D01*
G01X436772D02*
Y-297124D01*
X435205Y-293659D01*
G01X438339D02*
X436772Y-297124D01*
G01X441349Y-293659D02*
Y-298174D01*
X441662Y-299119D01*
X442289Y-299749D01*
X443072Y-299959D01*
X443855Y-299749D01*
X444482Y-299119D01*
X444795Y-298174D01*
Y-293659D01*
G01X447414Y-299959D02*
X449372Y-293659D01*
X451330Y-299959D01*
G01X450625Y-297754D02*
X448119D01*
G01X453870Y-299959D02*
Y-293659D01*
X457474Y-299959D01*
Y-293659D01*
G01X327870Y-289959D02*
Y-283659D01*
X331474Y-289959D01*
Y-283659D01*
G01X335972Y-289959D02*
X335345Y-289854D01*
X334797Y-289434D01*
X334327Y-288804D01*
X334014Y-288069D01*
X333857Y-287229D01*
Y-286389D01*
X334014Y-285549D01*
X334327Y-284814D01*
X334797Y-284184D01*
X335345Y-283764D01*
X335972Y-283659D01*
X336599Y-283764D01*
X337147Y-284184D01*
X337617Y-284814D01*
X337930Y-285549D01*
X338087Y-286389D01*
Y-287229D01*
X337930Y-288069D01*
X337617Y-288804D01*
X337147Y-289434D01*
X336599Y-289854D01*
X335972Y-289959D01*
G01X342272Y-290169D02*
X342115Y-290064D01*
Y-289854D01*
X342272Y-289749D01*
X342429Y-289854D01*
Y-290064D01*
X342272Y-290169D01*
G01X347084Y-284709D02*
X347554Y-284079D01*
X348102Y-283764D01*
X348729Y-283659D01*
X349512Y-283869D01*
X350060Y-284394D01*
X350217Y-285024D01*
X350139Y-285654D01*
X349825Y-286179D01*
X348259Y-287229D01*
X347554Y-287964D01*
X347084Y-289014D01*
X346927Y-289959D01*
X350217D01*
G01X354872D02*
Y-283659D01*
X353932Y-284919D01*
G01Y-289959D02*
X355812D01*
G01X361172D02*
Y-283659D01*
X360232Y-284919D01*
G01Y-289959D02*
X362112D01*
G01X367315Y-291114D02*
X367629Y-289749D01*
G01X371422Y-283659D02*
X372519Y-289959D01*
X373772Y-283659D01*
X375025Y-289959D01*
X376122Y-283659D01*
G01X381639Y-289959D02*
X378505D01*
Y-283659D01*
X381639D01*
G01X380385Y-286704D02*
X378505D01*
G01X384570Y-289959D02*
Y-283659D01*
X388174Y-289959D01*
Y-283659D01*
G01X391027Y-289959D02*
Y-283659D01*
G01X394317D02*
Y-289959D01*
G01Y-286809D02*
X391027D01*
G01X397249Y-283659D02*
Y-288174D01*
X397562Y-289119D01*
X398189Y-289749D01*
X398972Y-289959D01*
X399755Y-289749D01*
X400382Y-289119D01*
X400695Y-288174D01*
Y-283659D01*
G01X403314Y-289959D02*
X405272Y-283659D01*
X407230Y-289959D01*
G01X406525Y-287754D02*
X404019D01*
G01X416384Y-284709D02*
X416854Y-284079D01*
X417402Y-283764D01*
X418029Y-283659D01*
X418812Y-283869D01*
X419360Y-284394D01*
X419517Y-285024D01*
X419439Y-285654D01*
X419125Y-286179D01*
X417559Y-287229D01*
X416854Y-287964D01*
X416384Y-289014D01*
X416227Y-289959D01*
X419517D01*
G01X422370D02*
Y-283659D01*
X425974Y-289959D01*
Y-283659D01*
G01X428749Y-289959D02*
Y-283659D01*
X430315D01*
X430942Y-283974D01*
X431412Y-284394D01*
X431804Y-285024D01*
X432117Y-285759D01*
X432195Y-286809D01*
X432117Y-287859D01*
X431804Y-288594D01*
X431412Y-289224D01*
X430942Y-289644D01*
X430315Y-289959D01*
X428749D01*
G01X441505D02*
Y-283659D01*
X443464D01*
X444090Y-283974D01*
X444482Y-284394D01*
X444639Y-285234D01*
X444482Y-286074D01*
X444012Y-286599D01*
X443464Y-286914D01*
X441505D01*
G01X443464D02*
X444639Y-289959D01*
G01X447649D02*
Y-283659D01*
X449215D01*
X449842Y-283974D01*
X450312Y-284394D01*
X450704Y-285024D01*
X451017Y-285759D01*
X451095Y-286809D01*
X451017Y-287859D01*
X450704Y-288594D01*
X450312Y-289224D01*
X449842Y-289644D01*
X449215Y-289959D01*
X447649D01*
G01X455672Y-290169D02*
X455515Y-290064D01*
Y-289854D01*
X455672Y-289749D01*
X455829Y-289854D01*
Y-290064D01*
X455672Y-290169D01*
G01X351972Y-279259D02*
X349452Y-278842D01*
X347247Y-277176D01*
X345357Y-274676D01*
X344097Y-271759D01*
X343467Y-268426D01*
Y-265092D01*
X344097Y-261759D01*
X345357Y-258842D01*
X347247Y-256343D01*
X349452Y-254676D01*
X351972Y-254259D01*
X354492Y-254676D01*
X356697Y-256343D01*
X358587Y-258842D01*
X359847Y-261759D01*
X360477Y-265092D01*
Y-268426D01*
X359847Y-271759D01*
X358587Y-274676D01*
X356697Y-277176D01*
X354492Y-278842D01*
X351972Y-279259D01*
G01X354492Y-272592D02*
X358272Y-279259D01*
G01X371817Y-262593D02*
Y-274259D01*
X373077Y-277176D01*
X374967Y-278842D01*
X377172Y-279259D01*
X379377Y-278842D01*
X381267Y-277176D01*
X382527Y-274259D01*
G01Y-279259D02*
Y-262593D01*
G01X408042Y-279259D02*
Y-262593D01*
G01Y-265509D02*
X406782Y-263843D01*
X404892Y-263009D01*
X402687Y-262593D01*
X400482Y-263426D01*
X398592Y-265092D01*
X397332Y-267593D01*
X396702Y-270926D01*
X397332Y-274259D01*
X398592Y-276760D01*
X400482Y-278426D01*
X402687Y-279259D01*
X404892Y-278842D01*
X406782Y-277593D01*
X408042Y-275926D01*
G01X422217Y-279259D02*
Y-262593D01*
G01Y-266759D02*
X423477Y-264676D01*
X425367Y-263009D01*
X427887Y-262593D01*
X430092Y-263009D01*
X431982Y-264676D01*
X432927Y-267593D01*
Y-279259D01*
G01X452772Y-254259D02*
Y-279259D01*
G01X448362Y-262593D02*
X457182D01*
G01X483642Y-279259D02*
Y-262593D01*
G01Y-265509D02*
X482382Y-263843D01*
X480492Y-263009D01*
X478287Y-262593D01*
X476082Y-263426D01*
X474192Y-265092D01*
X472932Y-267593D01*
X472302Y-270926D01*
X472932Y-274259D01*
X474192Y-276760D01*
X476082Y-278426D01*
X478287Y-279259D01*
X480492Y-278842D01*
X482382Y-277593D01*
X483642Y-275926D01*
G01X523322Y-258959D02*
Y-266959D01*
X527322D01*
G01X535122D02*
Y-261626D01*
G01Y-262559D02*
X534722Y-262026D01*
X534122Y-261759D01*
X533422Y-261626D01*
X532722Y-261892D01*
X532122Y-262426D01*
X531722Y-263226D01*
X531522Y-264292D01*
X531722Y-265359D01*
X532122Y-266159D01*
X532722Y-266692D01*
X533422Y-266959D01*
X534122Y-266826D01*
X534722Y-266426D01*
X535122Y-265893D01*
G01X539222Y-269359D02*
X539822Y-269626D01*
X540622Y-269359D01*
X541122Y-268826D01*
X541522Y-268159D01*
X542122Y-266026D01*
X543422Y-261626D01*
G01X540222D02*
X542122Y-266026D01*
G01X547822Y-263359D02*
X551022D01*
X550722Y-262426D01*
X550222Y-261892D01*
X549522Y-261626D01*
X548822Y-261759D01*
X548222Y-262159D01*
X547822Y-263092D01*
X547622Y-263893D01*
Y-264692D01*
X547822Y-265492D01*
X548322Y-266292D01*
X548922Y-266826D01*
X549622Y-266959D01*
X550322Y-266692D01*
X551022Y-265893D01*
G01X555922Y-266959D02*
Y-261626D01*
G01Y-262692D02*
X556422Y-262159D01*
X556922Y-261759D01*
X557622Y-261626D01*
X558122Y-261759D01*
X558722Y-262159D01*
G01X542022Y-316959D02*
Y-308959D01*
X546622Y-316959D01*
Y-308959D01*
G01X552322Y-311626D02*
Y-316959D01*
G01Y-309492D02*
X552122Y-309359D01*
Y-309092D01*
X552322Y-308959D01*
X552522Y-309092D01*
Y-309359D01*
X552322Y-309492D01*
G01X558622Y-316959D02*
Y-311626D01*
G01Y-312959D02*
X559022Y-312292D01*
X559622Y-311759D01*
X560422Y-311626D01*
X561122Y-311759D01*
X561722Y-312292D01*
X562022Y-313226D01*
Y-316959D01*
G01X570122D02*
Y-311626D01*
G01Y-312559D02*
X569722Y-312026D01*
X569122Y-311759D01*
X568422Y-311626D01*
X567722Y-311892D01*
X567122Y-312426D01*
X566722Y-313226D01*
X566522Y-314292D01*
X566722Y-315359D01*
X567122Y-316159D01*
X567722Y-316692D01*
X568422Y-316959D01*
X569122Y-316826D01*
X569722Y-316426D01*
X570122Y-315893D01*
G01X554922Y-287959D02*
X556922D01*
Y-290359D01*
X556322Y-291159D01*
X555622Y-291692D01*
X554622Y-291959D01*
X553622Y-291692D01*
X552922Y-291159D01*
X552322Y-290359D01*
X551922Y-289426D01*
X551722Y-288359D01*
Y-287426D01*
X551922Y-286626D01*
X552322Y-285692D01*
X552922Y-284892D01*
X553522Y-284359D01*
X554322Y-283959D01*
X555022D01*
X555822Y-284226D01*
X556422Y-284759D01*
G01X560022Y-291959D02*
Y-283959D01*
X564622Y-291959D01*
Y-283959D01*
G01X568122Y-291959D02*
Y-283959D01*
X570122D01*
X570922Y-284359D01*
X571522Y-284892D01*
X572022Y-285692D01*
X572422Y-286626D01*
X572522Y-287959D01*
X572422Y-289292D01*
X572022Y-290226D01*
X571522Y-291026D01*
X570922Y-291559D01*
X570122Y-291959D01*
X568122D01*
G01X578322D02*
Y-283959D01*
X577122Y-285559D01*
G01Y-291959D02*
X579522D01*
G01X574622Y-265759D02*
X575222Y-266426D01*
X575922Y-266826D01*
X576822Y-266959D01*
X577722Y-266692D01*
X578422Y-266159D01*
X578922Y-265226D01*
X579022Y-264159D01*
X578822Y-263092D01*
X578322Y-262426D01*
X577622Y-261892D01*
X576922Y-261759D01*
X576222Y-261892D01*
X575322Y-262426D01*
X575622Y-258959D01*
X578322D01*
G01X649922Y-310292D02*
X650522Y-309492D01*
X651222Y-309092D01*
X652022Y-308959D01*
X653022Y-309226D01*
X653722Y-309892D01*
X653922Y-310692D01*
X653822Y-311493D01*
X653422Y-312159D01*
X651422Y-313492D01*
X650522Y-314426D01*
X649922Y-315759D01*
X649722Y-316959D01*
X653922D01*
G01X659822Y-308959D02*
X659022Y-309226D01*
X658422Y-309892D01*
X658022Y-310692D01*
X657722Y-311759D01*
X657622Y-312959D01*
X657722Y-314159D01*
X658022Y-315226D01*
X658422Y-316026D01*
X659022Y-316692D01*
X659822Y-316959D01*
X660622Y-316692D01*
X661222Y-316026D01*
X661622Y-315226D01*
X661922Y-314159D01*
X662022Y-312959D01*
X661922Y-311759D01*
X661622Y-310692D01*
X661222Y-309892D01*
X660622Y-309226D01*
X659822Y-308959D01*
G01X665922Y-310292D02*
X666522Y-309492D01*
X667222Y-309092D01*
X668022Y-308959D01*
X669022Y-309226D01*
X669722Y-309892D01*
X669922Y-310692D01*
X669822Y-311493D01*
X669422Y-312159D01*
X667422Y-313492D01*
X666522Y-314426D01*
X665922Y-315759D01*
X665722Y-316959D01*
X669922D01*
G01X673922Y-310292D02*
X674522Y-309492D01*
X675222Y-309092D01*
X676022Y-308959D01*
X677022Y-309226D01*
X677722Y-309892D01*
X677922Y-310692D01*
X677822Y-311493D01*
X677422Y-312159D01*
X675422Y-313492D01*
X674522Y-314426D01*
X673922Y-315759D01*
X673722Y-316959D01*
X677922D01*
G01X682022Y-317226D02*
X685622Y-308959D01*
G01X691822Y-316959D02*
Y-308959D01*
X690622Y-310559D01*
G01Y-316959D02*
X693022D01*
G01X697922Y-310292D02*
X698522Y-309492D01*
X699222Y-309092D01*
X700022Y-308959D01*
X701022Y-309226D01*
X701722Y-309892D01*
X701922Y-310692D01*
X701822Y-311493D01*
X701422Y-312159D01*
X699422Y-313492D01*
X698522Y-314426D01*
X697922Y-315759D01*
X697722Y-316959D01*
X701922D01*
G01X706022Y-317226D02*
X709622Y-308959D01*
G01X715822D02*
X715022Y-309226D01*
X714422Y-309892D01*
X714022Y-310692D01*
X713722Y-311759D01*
X713622Y-312959D01*
X713722Y-314159D01*
X714022Y-315226D01*
X714422Y-316026D01*
X715022Y-316692D01*
X715822Y-316959D01*
X716622Y-316692D01*
X717222Y-316026D01*
X717622Y-315226D01*
X717922Y-314159D01*
X718022Y-312959D01*
X717922Y-311759D01*
X717622Y-310692D01*
X717222Y-309892D01*
X716622Y-309226D01*
X715822Y-308959D01*
G01X722122Y-316026D02*
X722822Y-316692D01*
X723622Y-316959D01*
X724422Y-316692D01*
X725122Y-315893D01*
X725622Y-314692D01*
X725822Y-313492D01*
Y-312026D01*
X725622Y-310826D01*
X725122Y-309759D01*
X724522Y-309226D01*
X723822Y-308959D01*
X723022Y-309226D01*
X722422Y-309759D01*
X722022Y-310559D01*
X721822Y-311626D01*
X722022Y-312559D01*
X722522Y-313492D01*
X723122Y-314026D01*
X723822Y-314159D01*
X724622Y-313893D01*
X725222Y-313226D01*
X725822Y-312026D01*
G01X649622Y-291959D02*
Y-283959D01*
X651622D01*
X652422Y-284359D01*
X653022Y-284892D01*
X653522Y-285692D01*
X653922Y-286626D01*
X654022Y-287959D01*
X653922Y-289292D01*
X653522Y-290226D01*
X653022Y-291026D01*
X652422Y-291559D01*
X651622Y-291959D01*
X649622D01*
G01X657322D02*
X659822Y-283959D01*
X662322Y-291959D01*
G01X661422Y-289159D02*
X658222D01*
G01X667822Y-283959D02*
X667022Y-284226D01*
X666422Y-284892D01*
X666022Y-285692D01*
X665722Y-286759D01*
X665622Y-287959D01*
X665722Y-289159D01*
X666022Y-290226D01*
X666422Y-291026D01*
X667022Y-291692D01*
X667822Y-291959D01*
X668622Y-291692D01*
X669222Y-291026D01*
X669622Y-290226D01*
X669922Y-289159D01*
X670022Y-287959D01*
X669922Y-286759D01*
X669622Y-285692D01*
X669222Y-284892D01*
X668622Y-284226D01*
X667822Y-283959D01*
G01X673922Y-291959D02*
Y-283959D01*
X677722D01*
G01X676322Y-287826D02*
X673922D01*
G01X683822Y-283959D02*
X683022Y-284226D01*
X682422Y-284892D01*
X682022Y-285692D01*
X681722Y-286759D01*
X681622Y-287959D01*
X681722Y-289159D01*
X682022Y-290226D01*
X682422Y-291026D01*
X683022Y-291692D01*
X683822Y-291959D01*
X684622Y-291692D01*
X685222Y-291026D01*
X685622Y-290226D01*
X685922Y-289159D01*
X686022Y-287959D01*
X685922Y-286759D01*
X685622Y-285692D01*
X685222Y-284892D01*
X684622Y-284226D01*
X683822Y-283959D01*
G01X691822D02*
Y-291959D01*
G01X689522Y-283959D02*
X694122D01*
G01X697922Y-291959D02*
Y-283959D01*
X701722D01*
G01X700322Y-287826D02*
X697922D01*
G01X708622Y-287692D02*
X709022Y-287292D01*
X709322Y-286626D01*
X709522Y-285692D01*
X709322Y-284892D01*
X708922Y-284359D01*
X708222Y-283959D01*
X705522D01*
Y-291959D01*
X708822D01*
X709522Y-291426D01*
X709922Y-290626D01*
X710122Y-289692D01*
X709922Y-288759D01*
X709322Y-287959D01*
X708622Y-287692D01*
X705522D01*
G01X713922Y-288626D02*
X714622Y-287692D01*
X715222Y-287159D01*
X716022Y-286892D01*
X716722Y-287159D01*
X717222Y-287692D01*
X717622Y-288492D01*
X717722Y-289426D01*
X717622Y-290226D01*
X717222Y-291026D01*
X716622Y-291692D01*
X715922Y-291959D01*
X715122Y-291692D01*
X714422Y-290893D01*
X714022Y-289692D01*
X713922Y-288359D01*
X714122Y-286626D01*
X714422Y-285692D01*
X714922Y-284759D01*
X715622Y-284092D01*
X716322Y-283959D01*
X717022Y-284226D01*
X717522Y-284892D01*
G01X721622Y-291959D02*
Y-283959D01*
X723622D01*
X724422Y-284359D01*
X725022Y-284892D01*
X725522Y-285692D01*
X725922Y-286626D01*
X726022Y-287959D01*
X725922Y-289292D01*
X725522Y-290226D01*
X725022Y-291026D01*
X724422Y-291559D01*
X723622Y-291959D01*
X721622D01*
G01X731822Y-283959D02*
X731022Y-284226D01*
X730422Y-284892D01*
X730022Y-285692D01*
X729722Y-286759D01*
X729622Y-287959D01*
X729722Y-289159D01*
X730022Y-290226D01*
X730422Y-291026D01*
X731022Y-291692D01*
X731822Y-291959D01*
X732622Y-291692D01*
X733222Y-291026D01*
X733622Y-290226D01*
X733922Y-289159D01*
X734022Y-287959D01*
X733922Y-286759D01*
X733622Y-285692D01*
X733222Y-284892D01*
X732622Y-284226D01*
X731822Y-283959D01*
G01X649862Y-270000D02*
Y-263700D01*
X652838D01*
G01X651742Y-266745D02*
X649862D01*
G01X657650Y-263700D02*
X657023Y-263910D01*
X656553Y-264435D01*
X656240Y-265065D01*
X656005Y-265905D01*
X655927Y-266850D01*
X656005Y-267795D01*
X656240Y-268635D01*
X656553Y-269265D01*
X657023Y-269790D01*
X657650Y-270000D01*
X658277Y-269790D01*
X658747Y-269265D01*
X659060Y-268635D01*
X659295Y-267795D01*
X659373Y-266850D01*
X659295Y-265905D01*
X659060Y-265065D01*
X658747Y-264435D01*
X658277Y-263910D01*
X657650Y-263700D01*
G01X663950D02*
Y-270000D01*
G01X662148Y-263700D02*
X665752D01*
G01X667900Y-272100D02*
X672600D01*
G01X674983Y-270000D02*
Y-263700D01*
X676863D01*
X677490Y-264015D01*
X677960Y-264750D01*
X678117Y-265590D01*
X677960Y-266430D01*
X677568Y-267060D01*
X676863Y-267375D01*
X674983D01*
G01X684573Y-264225D02*
X684103Y-263910D01*
X683555Y-263700D01*
X682928D01*
X682223Y-264015D01*
X681675Y-264540D01*
X681283Y-265170D01*
X680970Y-266220D01*
X680892Y-267165D01*
X681048Y-268110D01*
X681283Y-268740D01*
X681753Y-269370D01*
X682302Y-269790D01*
X682850Y-270000D01*
X683398D01*
X683947Y-269790D01*
X684417Y-269475D01*
X684808Y-269055D01*
G01X689777Y-266640D02*
X690090Y-266325D01*
X690325Y-265800D01*
X690482Y-265065D01*
X690325Y-264435D01*
X690012Y-264015D01*
X689463Y-263700D01*
X687348D01*
Y-270000D01*
X689933D01*
X690482Y-269580D01*
X690795Y-268950D01*
X690952Y-268215D01*
X690795Y-267480D01*
X690325Y-266850D01*
X689777Y-266640D01*
X687348D01*
G01X693100Y-272100D02*
X697800D01*
G01X700262Y-270000D02*
Y-263700D01*
X703238D01*
G01X702142Y-266745D02*
X700262D01*
G01X706092Y-270000D02*
X708050Y-263700D01*
X710008Y-270000D01*
G01X709303Y-267795D02*
X706797D01*
G01X712548Y-270000D02*
Y-263700D01*
X716152Y-270000D01*
Y-263700D01*
G01X718300Y-272100D02*
X723000D01*
G01X727577Y-266640D02*
X727890Y-266325D01*
X728125Y-265800D01*
X728282Y-265065D01*
X728125Y-264435D01*
X727812Y-264015D01*
X727263Y-263700D01*
X725148D01*
Y-270000D01*
X727733D01*
X728282Y-269580D01*
X728595Y-268950D01*
X728752Y-268215D01*
X728595Y-267480D01*
X728125Y-266850D01*
X727577Y-266640D01*
X725148D01*
G01X733250Y-270000D02*
X732623Y-269895D01*
X732075Y-269475D01*
X731605Y-268845D01*
X731292Y-268110D01*
X731135Y-267270D01*
Y-266430D01*
X731292Y-265590D01*
X731605Y-264855D01*
X732075Y-264225D01*
X732623Y-263805D01*
X733250Y-263700D01*
X733877Y-263805D01*
X734425Y-264225D01*
X734895Y-264855D01*
X735208Y-265590D01*
X735365Y-266430D01*
Y-267270D01*
X735208Y-268110D01*
X734895Y-268845D01*
X734425Y-269475D01*
X733877Y-269895D01*
X733250Y-270000D01*
G01X737592D02*
X739550Y-263700D01*
X741508Y-270000D01*
G01X740803Y-267795D02*
X738297D01*
G01X744283Y-270000D02*
Y-263700D01*
X746242D01*
X746868Y-264015D01*
X747260Y-264435D01*
X747417Y-265275D01*
X747260Y-266115D01*
X746790Y-266640D01*
X746242Y-266955D01*
X744283D01*
G01X746242D02*
X747417Y-270000D01*
G01X750427D02*
Y-263700D01*
X751993D01*
X752620Y-264015D01*
X753090Y-264435D01*
X753482Y-265065D01*
X753795Y-265800D01*
X753873Y-266850D01*
X753795Y-267900D01*
X753482Y-268635D01*
X753090Y-269265D01*
X752620Y-269685D01*
X751993Y-270000D01*
X750427D01*
G01X756100Y-272100D02*
X760800D01*
G01X762713Y-270000D02*
Y-263700D01*
X764750Y-268950D01*
X766787Y-263700D01*
Y-270000D01*
G01X769483D02*
Y-263700D01*
X771363D01*
X771990Y-264015D01*
X772460Y-264750D01*
X772617Y-265590D01*
X772460Y-266430D01*
X772068Y-267060D01*
X771363Y-267375D01*
X769483D01*
G01X775627Y-269055D02*
X776097Y-269580D01*
X776645Y-269895D01*
X777350Y-270000D01*
X778055Y-269790D01*
X778603Y-269370D01*
X778995Y-268635D01*
X779073Y-267795D01*
X778917Y-266955D01*
X778525Y-266430D01*
X777977Y-266010D01*
X777428Y-265905D01*
X776880Y-266010D01*
X776175Y-266430D01*
X776410Y-263700D01*
X778525D01*
G01X783650D02*
X783023Y-263910D01*
X782553Y-264435D01*
X782240Y-265065D01*
X782005Y-265905D01*
X781927Y-266850D01*
X782005Y-267795D01*
X782240Y-268635D01*
X782553Y-269265D01*
X783023Y-269790D01*
X783650Y-270000D01*
X784277Y-269790D01*
X784747Y-269265D01*
X785060Y-268635D01*
X785295Y-267795D01*
X785373Y-266850D01*
X785295Y-265905D01*
X785060Y-265065D01*
X784747Y-264435D01*
X784277Y-263910D01*
X783650Y-263700D01*
G01X790890Y-270000D02*
Y-263700D01*
X787992Y-268215D01*
X791908D01*
G01X796250Y-270000D02*
X796798Y-269895D01*
X797425Y-269580D01*
X797817Y-269055D01*
X797973Y-268320D01*
X797817Y-267585D01*
X797347Y-266955D01*
X796642Y-266640D01*
X795858D01*
X795388Y-266430D01*
X794997Y-265905D01*
X794840Y-265170D01*
X795075Y-264435D01*
X795623Y-263910D01*
X796250Y-263700D01*
X796877Y-263910D01*
X797425Y-264435D01*
X797660Y-265170D01*
X797503Y-265905D01*
X797112Y-266430D01*
X796642Y-266640D01*
X795858D01*
X795153Y-266955D01*
X794683Y-267585D01*
X794527Y-268320D01*
X794683Y-269055D01*
X795075Y-269580D01*
X795702Y-269895D01*
X796250Y-270000D01*
G01X738322Y-319959D02*
Y-311959D01*
X737122Y-313559D01*
G01Y-319959D02*
X739522D01*
G01X744422Y-316626D02*
X745122Y-315692D01*
X745722Y-315159D01*
X746522Y-314892D01*
X747222Y-315159D01*
X747722Y-315692D01*
X748122Y-316492D01*
X748222Y-317426D01*
X748122Y-318226D01*
X747722Y-319026D01*
X747122Y-319692D01*
X746422Y-319959D01*
X745622Y-319692D01*
X744922Y-318893D01*
X744522Y-317692D01*
X744422Y-316359D01*
X744622Y-314626D01*
X744922Y-313692D01*
X745422Y-312759D01*
X746122Y-312092D01*
X746822Y-311959D01*
X747522Y-312226D01*
X748022Y-312892D01*
G01X754322Y-320226D02*
X754122Y-320092D01*
Y-319826D01*
X754322Y-319692D01*
X754522Y-319826D01*
Y-320092D01*
X754322Y-320226D01*
G01X760422Y-316626D02*
X761122Y-315692D01*
X761722Y-315159D01*
X762522Y-314892D01*
X763222Y-315159D01*
X763722Y-315692D01*
X764122Y-316492D01*
X764222Y-317426D01*
X764122Y-318226D01*
X763722Y-319026D01*
X763122Y-319692D01*
X762422Y-319959D01*
X761622Y-319692D01*
X760922Y-318893D01*
X760522Y-317692D01*
X760422Y-316359D01*
X760622Y-314626D01*
X760922Y-313692D01*
X761422Y-312759D01*
X762122Y-312092D01*
X762822Y-311959D01*
X763522Y-312226D01*
X764022Y-312892D01*
G01X783322Y-319959D02*
Y-311959D01*
X782122Y-313559D01*
G01Y-319959D02*
X784522D01*
G01X791122D02*
X791322Y-318226D01*
X791622Y-316759D01*
X792022Y-315426D01*
X792522Y-313959D01*
X793322Y-311959D01*
X789322D01*
G01X799322Y-320226D02*
X799122Y-320092D01*
Y-319826D01*
X799322Y-319692D01*
X799522Y-319826D01*
Y-320092D01*
X799322Y-320226D01*
G01X805422Y-313292D02*
X806022Y-312492D01*
X806722Y-312092D01*
X807522Y-311959D01*
X808522Y-312226D01*
X809222Y-312892D01*
X809422Y-313692D01*
X809322Y-314493D01*
X808922Y-315159D01*
X806922Y-316492D01*
X806022Y-317426D01*
X805422Y-318759D01*
X805222Y-319959D01*
X809422D01*
G01X803122Y-294959D02*
Y-286959D01*
X805122D01*
X805922Y-287359D01*
X806522Y-287892D01*
X807022Y-288692D01*
X807422Y-289626D01*
X807522Y-290959D01*
X807422Y-292292D01*
X807022Y-293226D01*
X806522Y-294026D01*
X805922Y-294559D01*
X805122Y-294959D01*
X803122D01*
M02*
